FILE_TYPE = MACRO_DRAWING;
SET COLOR_WIRE YELLOW;
SET COLOR_PROP MONO;
SET COLOR_DOT WHITE;
SET COLOR_ARC YELLOW;
SET COLOR_BODY GREEN;
SET COLOR_NOTE MONO;
SET PROP_DISPLAY VALUE;
SET PAGE_NUMBER P81;
FORCEADD OFFPAGE..3
(1550 5150);
FORCEPROP 2 LAST $XR0 59 
J 0
(1764 5150);
DISPLAY 0.638298 (1764 5150);
PAINT MONO (1764 5150);
FORCEPROP 2 LAST $XR1 82 
J 0
(1854 5150);
DISPLAY 0.638298 (1854 5150);
PAINT MONO (1854 5150);
FORCEPROP 2 LAST CDS_LIB mstr_standard
J 0
(1550 5150);
DISPLAY 0.787234 (1550 5150);
PAINT MONO (1550 5150);
DISPLAY INVISIBLE (1550 5150);
FORCEPROP 1 LAST OFFPAGE TRUE
J 0
(1875 5025);
DISPLAY 0.936170 (1875 5025);
PAINT GREEN (1875 5025);
DISPLAY INVISIBLE (1875 5025);
FORCEPROP 1 LAST COMMENT_BODY TRUE
J 0
(1500 5050);
DISPLAY 0.936170 (1500 5050);
PAINT GREEN (1500 5050);
DISPLAY INVISIBLE (1500 5050);
FORCEPROP 2 LAST PATH I1
J 0
(1750 5225);
DISPLAY 0.787234 (1750 5225);
PAINT MONO (1750 5225);
DISPLAY INVISIBLE (1750 5225);
FORCEADD TAP..6
R 2
(850 4700);
FORCEPROP 3 LASTPIN (800 4700) SIG_NAME M_J_DQS_DN<13>
J 0
(810 4710);
DISPLAY 0.659574 (810 4710);
PAINT MONO (810 4710);
DISPLAY INVISIBLE (810 4710);
FORCEPROP 1 LASTPIN (800 4700) BN 13
J 2
(850 4710);
DISPLAY 0.617021 (850 4710);
PAINT PINK (850 4710);
FORCEPROP 2 LAST CDS_LIB mstr_standard
J 0
(850 4700);
DISPLAY 0.787234 (850 4700);
PAINT MONO (850 4700);
DISPLAY INVISIBLE (850 4700);
FORCEPROP 1 LAST BODY_TYPE PLUMBING
J 2
(850 4650);
DISPLAY 1.234043 (850 4650);
PAINT GREEN (850 4650);
DISPLAY INVISIBLE (850 4650);
FORCEPROP 1 LAST HDL_TAP TRUE
J 2
(525 4575);
DISPLAY 1.234043 (525 4575);
PAINT GREEN (525 4575);
DISPLAY INVISIBLE (525 4575);
FORCEPROP 1 LAST PATH I10
J 2
(850 4700);
DISPLAY 0.936170 (850 4700);
PAINT GREEN (850 4700);
DISPLAY INVISIBLE (850 4700);
FORCEADD TAP..6
R 2
(-1800 2150);
FORCEPROP 3 LASTPIN (-1850 2150) SIG_NAME M_J_DQ<11>
J 0
(-1840 2160);
DISPLAY 0.659574 (-1840 2160);
PAINT MONO (-1840 2160);
DISPLAY INVISIBLE (-1840 2160);
FORCEPROP 1 LASTPIN (-1850 2150) BN 11
J 2
(-1800 2160);
DISPLAY 0.617021 (-1800 2160);
PAINT PINK (-1800 2160);
FORCEPROP 2 LAST CDS_LIB mstr_standard
J 2
(-1800 2150);
DISPLAY 0.787234 (-1800 2150);
PAINT MONO (-1800 2150);
DISPLAY INVISIBLE (-1800 2150);
FORCEPROP 1 LAST BODY_TYPE PLUMBING
J 2
(-1800 2100);
DISPLAY 1.234043 (-1800 2100);
PAINT GREEN (-1800 2100);
DISPLAY INVISIBLE (-1800 2100);
FORCEPROP 1 LAST HDL_TAP TRUE
J 2
(-2125 2025);
DISPLAY 1.234043 (-2125 2025);
PAINT GREEN (-2125 2025);
DISPLAY INVISIBLE (-2125 2025);
FORCEPROP 1 LAST PATH I100
J 2
(-1800 2150);
DISPLAY 0.936170 (-1800 2150);
PAINT GREEN (-1800 2150);
DISPLAY INVISIBLE (-1800 2150);
FORCEADD TAP..6
R 2
(-1800 2100);
FORCEPROP 3 LASTPIN (-1850 2100) SIG_NAME M_J_DQ<8>
J 0
(-1840 2110);
DISPLAY 0.659574 (-1840 2110);
PAINT MONO (-1840 2110);
DISPLAY INVISIBLE (-1840 2110);
FORCEPROP 1 LASTPIN (-1850 2100) BN 8
J 2
(-1800 2110);
DISPLAY 0.617021 (-1800 2110);
PAINT PINK (-1800 2110);
FORCEPROP 2 LAST CDS_LIB mstr_standard
J 2
(-1800 2100);
DISPLAY 0.787234 (-1800 2100);
PAINT MONO (-1800 2100);
DISPLAY INVISIBLE (-1800 2100);
FORCEPROP 1 LAST BODY_TYPE PLUMBING
J 2
(-1800 2050);
DISPLAY 1.234043 (-1800 2050);
PAINT GREEN (-1800 2050);
DISPLAY INVISIBLE (-1800 2050);
FORCEPROP 1 LAST HDL_TAP TRUE
J 2
(-2125 1975);
DISPLAY 1.234043 (-2125 1975);
PAINT GREEN (-2125 1975);
DISPLAY INVISIBLE (-2125 1975);
FORCEPROP 1 LAST PATH I101
J 2
(-1800 2100);
DISPLAY 0.936170 (-1800 2100);
PAINT GREEN (-1800 2100);
DISPLAY INVISIBLE (-1800 2100);
FORCEADD TAP..6
R 2
(-1800 2050);
FORCEPROP 3 LASTPIN (-1850 2050) SIG_NAME M_J_DQ<9>
J 0
(-1840 2060);
DISPLAY 0.659574 (-1840 2060);
PAINT MONO (-1840 2060);
DISPLAY INVISIBLE (-1840 2060);
FORCEPROP 1 LASTPIN (-1850 2050) BN 9
J 2
(-1800 2060);
DISPLAY 0.617021 (-1800 2060);
PAINT PINK (-1800 2060);
FORCEPROP 2 LAST CDS_LIB mstr_standard
J 2
(-1800 2050);
DISPLAY 0.787234 (-1800 2050);
PAINT MONO (-1800 2050);
DISPLAY INVISIBLE (-1800 2050);
FORCEPROP 1 LAST BODY_TYPE PLUMBING
J 2
(-1800 2000);
DISPLAY 1.234043 (-1800 2000);
PAINT GREEN (-1800 2000);
DISPLAY INVISIBLE (-1800 2000);
FORCEPROP 1 LAST HDL_TAP TRUE
J 2
(-2125 1925);
DISPLAY 1.234043 (-2125 1925);
PAINT GREEN (-2125 1925);
DISPLAY INVISIBLE (-2125 1925);
FORCEPROP 1 LAST PATH I102
J 2
(-1800 2050);
DISPLAY 0.936170 (-1800 2050);
PAINT GREEN (-1800 2050);
DISPLAY INVISIBLE (-1800 2050);
FORCEADD TAP..6
R 2
(-1800 2000);
FORCEPROP 3 LASTPIN (-1850 2000) SIG_NAME M_J_DQ<6>
J 0
(-1840 2010);
DISPLAY 0.659574 (-1840 2010);
PAINT MONO (-1840 2010);
DISPLAY INVISIBLE (-1840 2010);
FORCEPROP 1 LASTPIN (-1850 2000) BN 6
J 2
(-1800 2010);
DISPLAY 0.617021 (-1800 2010);
PAINT PINK (-1800 2010);
FORCEPROP 2 LAST CDS_LIB mstr_standard
J 2
(-1800 2000);
DISPLAY 0.787234 (-1800 2000);
PAINT MONO (-1800 2000);
DISPLAY INVISIBLE (-1800 2000);
FORCEPROP 1 LAST BODY_TYPE PLUMBING
J 2
(-1800 1950);
DISPLAY 1.234043 (-1800 1950);
PAINT GREEN (-1800 1950);
DISPLAY INVISIBLE (-1800 1950);
FORCEPROP 1 LAST HDL_TAP TRUE
J 2
(-2125 1875);
DISPLAY 1.234043 (-2125 1875);
PAINT GREEN (-2125 1875);
DISPLAY INVISIBLE (-2125 1875);
FORCEPROP 1 LAST PATH I103
J 2
(-1800 2000);
DISPLAY 0.936170 (-1800 2000);
PAINT GREEN (-1800 2000);
DISPLAY INVISIBLE (-1800 2000);
FORCEADD TAP..6
R 2
(-1800 1750);
FORCEPROP 3 LASTPIN (-1850 1750) SIG_NAME M_J_DQ<3>
J 0
(-1840 1760);
DISPLAY 0.659574 (-1840 1760);
PAINT MONO (-1840 1760);
DISPLAY INVISIBLE (-1840 1760);
FORCEPROP 1 LASTPIN (-1850 1750) BN 3
J 2
(-1800 1760);
DISPLAY 0.617021 (-1800 1760);
PAINT PINK (-1800 1760);
FORCEPROP 2 LAST CDS_LIB mstr_standard
J 2
(-1800 1750);
DISPLAY 0.787234 (-1800 1750);
PAINT MONO (-1800 1750);
DISPLAY INVISIBLE (-1800 1750);
FORCEPROP 1 LAST BODY_TYPE PLUMBING
J 2
(-1800 1700);
DISPLAY 1.234043 (-1800 1700);
PAINT GREEN (-1800 1700);
DISPLAY INVISIBLE (-1800 1700);
FORCEPROP 1 LAST HDL_TAP TRUE
J 2
(-2125 1625);
DISPLAY 1.234043 (-2125 1625);
PAINT GREEN (-2125 1625);
DISPLAY INVISIBLE (-2125 1625);
FORCEPROP 1 LAST PATH I104
J 2
(-1800 1750);
DISPLAY 0.936170 (-1800 1750);
PAINT GREEN (-1800 1750);
DISPLAY INVISIBLE (-1800 1750);
FORCEADD TAP..6
R 2
(-1800 1850);
FORCEPROP 3 LASTPIN (-1850 1850) SIG_NAME M_J_DQ<5>
J 0
(-1840 1860);
DISPLAY 0.659574 (-1840 1860);
PAINT MONO (-1840 1860);
DISPLAY INVISIBLE (-1840 1860);
FORCEPROP 1 LASTPIN (-1850 1850) BN 5
J 2
(-1800 1860);
DISPLAY 0.617021 (-1800 1860);
PAINT PINK (-1800 1860);
FORCEPROP 2 LAST CDS_LIB mstr_standard
J 2
(-1800 1850);
DISPLAY 0.787234 (-1800 1850);
PAINT MONO (-1800 1850);
DISPLAY INVISIBLE (-1800 1850);
FORCEPROP 1 LAST BODY_TYPE PLUMBING
J 2
(-1800 1800);
DISPLAY 1.234043 (-1800 1800);
PAINT GREEN (-1800 1800);
DISPLAY INVISIBLE (-1800 1800);
FORCEPROP 1 LAST HDL_TAP TRUE
J 2
(-2125 1725);
DISPLAY 1.234043 (-2125 1725);
PAINT GREEN (-2125 1725);
DISPLAY INVISIBLE (-2125 1725);
FORCEPROP 1 LAST PATH I105
J 2
(-1800 1850);
DISPLAY 0.936170 (-1800 1850);
PAINT GREEN (-1800 1850);
DISPLAY INVISIBLE (-1800 1850);
FORCEADD TAP..6
R 2
(-1800 1800);
FORCEPROP 3 LASTPIN (-1850 1800) SIG_NAME M_J_DQ<2>
J 0
(-1840 1810);
DISPLAY 0.659574 (-1840 1810);
PAINT MONO (-1840 1810);
DISPLAY INVISIBLE (-1840 1810);
FORCEPROP 1 LASTPIN (-1850 1800) BN 2
J 2
(-1800 1810);
DISPLAY 0.617021 (-1800 1810);
PAINT PINK (-1800 1810);
FORCEPROP 2 LAST CDS_LIB mstr_standard
J 2
(-1800 1800);
DISPLAY 0.787234 (-1800 1800);
PAINT MONO (-1800 1800);
DISPLAY INVISIBLE (-1800 1800);
FORCEPROP 1 LAST BODY_TYPE PLUMBING
J 2
(-1800 1750);
DISPLAY 1.234043 (-1800 1750);
PAINT GREEN (-1800 1750);
DISPLAY INVISIBLE (-1800 1750);
FORCEPROP 1 LAST HDL_TAP TRUE
J 2
(-2125 1675);
DISPLAY 1.234043 (-2125 1675);
PAINT GREEN (-2125 1675);
DISPLAY INVISIBLE (-2125 1675);
FORCEPROP 1 LAST PATH I106
J 2
(-1800 1800);
DISPLAY 0.936170 (-1800 1800);
PAINT GREEN (-1800 1800);
DISPLAY INVISIBLE (-1800 1800);
FORCEADD TAP..6
R 2
(-1800 1950);
FORCEPROP 3 LASTPIN (-1850 1950) SIG_NAME M_J_DQ<7>
J 0
(-1840 1960);
DISPLAY 0.659574 (-1840 1960);
PAINT MONO (-1840 1960);
DISPLAY INVISIBLE (-1840 1960);
FORCEPROP 1 LASTPIN (-1850 1950) BN 7
J 2
(-1800 1960);
DISPLAY 0.617021 (-1800 1960);
PAINT PINK (-1800 1960);
FORCEPROP 2 LAST CDS_LIB mstr_standard
J 2
(-1800 1950);
DISPLAY 0.787234 (-1800 1950);
PAINT MONO (-1800 1950);
DISPLAY INVISIBLE (-1800 1950);
FORCEPROP 1 LAST BODY_TYPE PLUMBING
J 2
(-1800 1900);
DISPLAY 1.234043 (-1800 1900);
PAINT GREEN (-1800 1900);
DISPLAY INVISIBLE (-1800 1900);
FORCEPROP 1 LAST HDL_TAP TRUE
J 2
(-2125 1825);
DISPLAY 1.234043 (-2125 1825);
PAINT GREEN (-2125 1825);
DISPLAY INVISIBLE (-2125 1825);
FORCEPROP 1 LAST PATH I107
J 2
(-1800 1950);
DISPLAY 0.936170 (-1800 1950);
PAINT GREEN (-1800 1950);
DISPLAY INVISIBLE (-1800 1950);
FORCEADD TAP..6
R 2
(-1800 1900);
FORCEPROP 3 LASTPIN (-1850 1900) SIG_NAME M_J_DQ<4>
J 0
(-1840 1910);
DISPLAY 0.659574 (-1840 1910);
PAINT MONO (-1840 1910);
DISPLAY INVISIBLE (-1840 1910);
FORCEPROP 1 LASTPIN (-1850 1900) BN 4
J 2
(-1800 1910);
DISPLAY 0.617021 (-1800 1910);
PAINT PINK (-1800 1910);
FORCEPROP 2 LAST CDS_LIB mstr_standard
J 2
(-1800 1900);
DISPLAY 0.787234 (-1800 1900);
PAINT MONO (-1800 1900);
DISPLAY INVISIBLE (-1800 1900);
FORCEPROP 1 LAST BODY_TYPE PLUMBING
J 2
(-1800 1850);
DISPLAY 1.234043 (-1800 1850);
PAINT GREEN (-1800 1850);
DISPLAY INVISIBLE (-1800 1850);
FORCEPROP 1 LAST HDL_TAP TRUE
J 2
(-2125 1775);
DISPLAY 1.234043 (-2125 1775);
PAINT GREEN (-2125 1775);
DISPLAY INVISIBLE (-2125 1775);
FORCEPROP 1 LAST PATH I108
J 2
(-1800 1900);
DISPLAY 0.936170 (-1800 1900);
PAINT GREEN (-1800 1900);
DISPLAY INVISIBLE (-1800 1900);
FORCEADD TAP..6
R 2
(-1800 1700);
FORCEPROP 3 LASTPIN (-1850 1700) SIG_NAME M_J_DQ<0>
J 0
(-1840 1710);
DISPLAY 0.659574 (-1840 1710);
PAINT MONO (-1840 1710);
DISPLAY INVISIBLE (-1840 1710);
FORCEPROP 1 LASTPIN (-1850 1700) BN 0
J 2
(-1800 1710);
DISPLAY 0.617021 (-1800 1710);
PAINT PINK (-1800 1710);
FORCEPROP 2 LAST CDS_LIB mstr_standard
J 2
(-1800 1700);
DISPLAY 0.787234 (-1800 1700);
PAINT MONO (-1800 1700);
DISPLAY INVISIBLE (-1800 1700);
FORCEPROP 1 LAST BODY_TYPE PLUMBING
J 2
(-1800 1650);
DISPLAY 1.234043 (-1800 1650);
PAINT GREEN (-1800 1650);
DISPLAY INVISIBLE (-1800 1650);
FORCEPROP 1 LAST HDL_TAP TRUE
J 2
(-2125 1575);
DISPLAY 1.234043 (-2125 1575);
PAINT GREEN (-2125 1575);
DISPLAY INVISIBLE (-2125 1575);
FORCEPROP 1 LAST PATH I109
J 2
(-1800 1700);
DISPLAY 0.936170 (-1800 1700);
PAINT GREEN (-1800 1700);
DISPLAY INVISIBLE (-1800 1700);
FORCEADD TAP..6
R 2
(850 4500);
FORCEPROP 3 LASTPIN (800 4500) SIG_NAME M_J_DQS_DN<11>
J 0
(810 4510);
DISPLAY 0.659574 (810 4510);
PAINT MONO (810 4510);
DISPLAY INVISIBLE (810 4510);
FORCEPROP 1 LASTPIN (800 4500) BN 11
J 2
(850 4510);
DISPLAY 0.617021 (850 4510);
PAINT PINK (850 4510);
FORCEPROP 2 LAST CDS_LIB mstr_standard
J 0
(850 4500);
DISPLAY 0.787234 (850 4500);
PAINT MONO (850 4500);
DISPLAY INVISIBLE (850 4500);
FORCEPROP 1 LAST BODY_TYPE PLUMBING
J 2
(850 4450);
DISPLAY 1.234043 (850 4450);
PAINT GREEN (850 4450);
DISPLAY INVISIBLE (850 4450);
FORCEPROP 1 LAST HDL_TAP TRUE
J 2
(525 4375);
DISPLAY 1.234043 (525 4375);
PAINT GREEN (525 4375);
DISPLAY INVISIBLE (525 4375);
FORCEPROP 1 LAST PATH I11
J 2
(850 4500);
DISPLAY 0.936170 (850 4500);
PAINT GREEN (850 4500);
DISPLAY INVISIBLE (850 4500);
FORCEADD TAP..6
R 2
(-1800 1650);
FORCEPROP 3 LASTPIN (-1850 1650) SIG_NAME M_J_DQ<1>
J 0
(-1840 1660);
DISPLAY 0.659574 (-1840 1660);
PAINT MONO (-1840 1660);
DISPLAY INVISIBLE (-1840 1660);
FORCEPROP 1 LASTPIN (-1850 1650) BN 1
J 2
(-1800 1660);
DISPLAY 0.617021 (-1800 1660);
PAINT PINK (-1800 1660);
FORCEPROP 2 LAST CDS_LIB mstr_standard
J 2
(-1800 1650);
DISPLAY 0.787234 (-1800 1650);
PAINT MONO (-1800 1650);
DISPLAY INVISIBLE (-1800 1650);
FORCEPROP 1 LAST BODY_TYPE PLUMBING
J 2
(-1800 1600);
DISPLAY 1.234043 (-1800 1600);
PAINT GREEN (-1800 1600);
DISPLAY INVISIBLE (-1800 1600);
FORCEPROP 1 LAST HDL_TAP TRUE
J 2
(-2125 1525);
DISPLAY 1.234043 (-2125 1525);
PAINT GREEN (-2125 1525);
DISPLAY INVISIBLE (-2125 1525);
FORCEPROP 1 LAST PATH I110
J 2
(-1800 1650);
DISPLAY 0.936170 (-1800 1650);
PAINT GREEN (-1800 1650);
DISPLAY INVISIBLE (-1800 1650);
FORCEADD TAP..6
(-3300 4800);
FORCEPROP 3 LASTPIN (-3250 4800) SIG_NAME M_J_MA<17>
J 0
(-3240 4810);
DISPLAY 0.659574 (-3240 4810);
PAINT MONO (-3240 4810);
DISPLAY INVISIBLE (-3240 4810);
FORCEPROP 1 LASTPIN (-3250 4800) BN 17
J 0
(-3300 4810);
DISPLAY 0.617021 (-3300 4810);
PAINT PINK (-3300 4810);
FORCEPROP 2 LAST CDS_LIB mstr_standard
J 0
(-3300 4800);
DISPLAY 0.787234 (-3300 4800);
PAINT MONO (-3300 4800);
DISPLAY INVISIBLE (-3300 4800);
FORCEPROP 1 LAST BODY_TYPE PLUMBING
J 0
(-3300 4750);
DISPLAY 1.234043 (-3300 4750);
PAINT GREEN (-3300 4750);
DISPLAY INVISIBLE (-3300 4750);
FORCEPROP 1 LAST HDL_TAP TRUE
J 0
(-2975 4675);
DISPLAY 1.234043 (-2975 4675);
PAINT GREEN (-2975 4675);
DISPLAY INVISIBLE (-2975 4675);
FORCEPROP 1 LAST PATH I112
J 0
(-3300 4800);
DISPLAY 0.936170 (-3300 4800);
PAINT GREEN (-3300 4800);
DISPLAY INVISIBLE (-3300 4800);
FORCEADD OFFPAGE..1
(-3950 4850);
FORCEPROP 2 LAST $XR0 59 
J 0
(-4171 4850);
DISPLAY 0.638298 (-4171 4850);
PAINT MONO (-4171 4850);
FORCEPROP 2 LAST $XR1 82 
J 0
(-4261 4850);
DISPLAY 0.638298 (-4261 4850);
PAINT MONO (-4261 4850);
FORCEPROP 2 LAST CDS_LIB mstr_standard
J 0
(-3950 4850);
DISPLAY 0.787234 (-3950 4850);
PAINT MONO (-3950 4850);
DISPLAY INVISIBLE (-3950 4850);
FORCEPROP 1 LAST OFFPAGE TRUE
J 0
(-3625 4725);
DISPLAY 0.936170 (-3625 4725);
PAINT GREEN (-3625 4725);
DISPLAY INVISIBLE (-3625 4725);
FORCEPROP 1 LAST COMMENT_BODY TRUE
J 0
(-3825 4750);
DISPLAY 0.936170 (-3825 4750);
PAINT GREEN (-3825 4750);
DISPLAY INVISIBLE (-3825 4750);
FORCEPROP 2 LAST PATH I113
J 0
(-3900 4925);
DISPLAY 0.787234 (-3900 4925);
PAINT MONO (-3900 4925);
DISPLAY INVISIBLE (-3900 4925);
FORCEADD TAP..6
(-3300 4750);
FORCEPROP 3 LASTPIN (-3250 4750) SIG_NAME M_J_MA<16>
J 0
(-3240 4760);
DISPLAY 0.659574 (-3240 4760);
PAINT MONO (-3240 4760);
DISPLAY INVISIBLE (-3240 4760);
FORCEPROP 1 LASTPIN (-3250 4750) BN 16
J 0
(-3300 4760);
DISPLAY 0.617021 (-3300 4760);
PAINT PINK (-3300 4760);
FORCEPROP 2 LAST CDS_LIB mstr_standard
J 2
(-3300 4750);
DISPLAY 0.787234 (-3300 4750);
PAINT MONO (-3300 4750);
DISPLAY INVISIBLE (-3300 4750);
FORCEPROP 1 LAST BODY_TYPE PLUMBING
J 0
(-3300 4700);
DISPLAY 1.234043 (-3300 4700);
PAINT GREEN (-3300 4700);
DISPLAY INVISIBLE (-3300 4700);
FORCEPROP 1 LAST HDL_TAP TRUE
J 0
(-2975 4625);
DISPLAY 1.234043 (-2975 4625);
PAINT GREEN (-2975 4625);
DISPLAY INVISIBLE (-2975 4625);
FORCEPROP 1 LAST PATH I114
J 0
(-3300 4750);
DISPLAY 0.936170 (-3300 4750);
PAINT GREEN (-3300 4750);
DISPLAY INVISIBLE (-3300 4750);
FORCEADD TAP..6
(-3300 4700);
FORCEPROP 3 LASTPIN (-3250 4700) SIG_NAME M_J_MA<15>
J 0
(-3240 4710);
DISPLAY 0.659574 (-3240 4710);
PAINT MONO (-3240 4710);
DISPLAY INVISIBLE (-3240 4710);
FORCEPROP 1 LASTPIN (-3250 4700) BN 15
J 0
(-3300 4710);
DISPLAY 0.617021 (-3300 4710);
PAINT PINK (-3300 4710);
FORCEPROP 2 LAST CDS_LIB mstr_standard
J 2
(-3300 4700);
DISPLAY 0.787234 (-3300 4700);
PAINT MONO (-3300 4700);
DISPLAY INVISIBLE (-3300 4700);
FORCEPROP 1 LAST BODY_TYPE PLUMBING
J 0
(-3300 4650);
DISPLAY 1.234043 (-3300 4650);
PAINT GREEN (-3300 4650);
DISPLAY INVISIBLE (-3300 4650);
FORCEPROP 1 LAST HDL_TAP TRUE
J 0
(-2975 4575);
DISPLAY 1.234043 (-2975 4575);
PAINT GREEN (-2975 4575);
DISPLAY INVISIBLE (-2975 4575);
FORCEPROP 1 LAST PATH I115
J 0
(-3300 4700);
DISPLAY 0.936170 (-3300 4700);
PAINT GREEN (-3300 4700);
DISPLAY INVISIBLE (-3300 4700);
FORCEADD TAP..6
(-3300 4650);
FORCEPROP 3 LASTPIN (-3250 4650) SIG_NAME M_J_MA<14>
J 0
(-3240 4660);
DISPLAY 0.659574 (-3240 4660);
PAINT MONO (-3240 4660);
DISPLAY INVISIBLE (-3240 4660);
FORCEPROP 1 LASTPIN (-3250 4650) BN 14
J 0
(-3300 4660);
DISPLAY 0.617021 (-3300 4660);
PAINT PINK (-3300 4660);
FORCEPROP 2 LAST CDS_LIB mstr_standard
J 2
(-3300 4650);
DISPLAY 0.787234 (-3300 4650);
PAINT MONO (-3300 4650);
DISPLAY INVISIBLE (-3300 4650);
FORCEPROP 1 LAST BODY_TYPE PLUMBING
J 0
(-3300 4600);
DISPLAY 1.234043 (-3300 4600);
PAINT GREEN (-3300 4600);
DISPLAY INVISIBLE (-3300 4600);
FORCEPROP 1 LAST HDL_TAP TRUE
J 0
(-2975 4525);
DISPLAY 1.234043 (-2975 4525);
PAINT GREEN (-2975 4525);
DISPLAY INVISIBLE (-2975 4525);
FORCEPROP 1 LAST PATH I116
J 0
(-3300 4650);
DISPLAY 0.936170 (-3300 4650);
PAINT GREEN (-3300 4650);
DISPLAY INVISIBLE (-3300 4650);
FORCEADD TAP..6
(-3300 4600);
FORCEPROP 3 LASTPIN (-3250 4600) SIG_NAME M_J_MA<13>
J 0
(-3240 4610);
DISPLAY 0.659574 (-3240 4610);
PAINT MONO (-3240 4610);
DISPLAY INVISIBLE (-3240 4610);
FORCEPROP 1 LASTPIN (-3250 4600) BN 13
J 0
(-3300 4610);
DISPLAY 0.617021 (-3300 4610);
PAINT PINK (-3300 4610);
FORCEPROP 2 LAST CDS_LIB mstr_standard
J 2
(-3300 4600);
DISPLAY 0.787234 (-3300 4600);
PAINT MONO (-3300 4600);
DISPLAY INVISIBLE (-3300 4600);
FORCEPROP 1 LAST BODY_TYPE PLUMBING
J 0
(-3300 4550);
DISPLAY 1.234043 (-3300 4550);
PAINT GREEN (-3300 4550);
DISPLAY INVISIBLE (-3300 4550);
FORCEPROP 1 LAST HDL_TAP TRUE
J 0
(-2975 4475);
DISPLAY 1.234043 (-2975 4475);
PAINT GREEN (-2975 4475);
DISPLAY INVISIBLE (-2975 4475);
FORCEPROP 1 LAST PATH I117
J 0
(-3300 4600);
DISPLAY 0.936170 (-3300 4600);
PAINT GREEN (-3300 4600);
DISPLAY INVISIBLE (-3300 4600);
FORCEADD TAP..6
(-3300 4550);
FORCEPROP 3 LASTPIN (-3250 4550) SIG_NAME M_J_MA<12>
J 0
(-3240 4560);
DISPLAY 0.659574 (-3240 4560);
PAINT MONO (-3240 4560);
DISPLAY INVISIBLE (-3240 4560);
FORCEPROP 1 LASTPIN (-3250 4550) BN 12
J 0
(-3300 4560);
DISPLAY 0.617021 (-3300 4560);
PAINT PINK (-3300 4560);
FORCEPROP 2 LAST CDS_LIB mstr_standard
J 2
(-3300 4550);
DISPLAY 0.787234 (-3300 4550);
PAINT MONO (-3300 4550);
DISPLAY INVISIBLE (-3300 4550);
FORCEPROP 1 LAST BODY_TYPE PLUMBING
J 0
(-3300 4500);
DISPLAY 1.234043 (-3300 4500);
PAINT GREEN (-3300 4500);
DISPLAY INVISIBLE (-3300 4500);
FORCEPROP 1 LAST HDL_TAP TRUE
J 0
(-2975 4425);
DISPLAY 1.234043 (-2975 4425);
PAINT GREEN (-2975 4425);
DISPLAY INVISIBLE (-2975 4425);
FORCEPROP 1 LAST PATH I118
J 0
(-3300 4550);
DISPLAY 0.936170 (-3300 4550);
PAINT GREEN (-3300 4550);
DISPLAY INVISIBLE (-3300 4550);
FORCEADD TAP..6
(-3300 4500);
FORCEPROP 3 LASTPIN (-3250 4500) SIG_NAME M_J_MA<11>
J 0
(-3240 4510);
DISPLAY 0.659574 (-3240 4510);
PAINT MONO (-3240 4510);
DISPLAY INVISIBLE (-3240 4510);
FORCEPROP 1 LASTPIN (-3250 4500) BN 11
J 0
(-3300 4510);
DISPLAY 0.617021 (-3300 4510);
PAINT PINK (-3300 4510);
FORCEPROP 2 LAST CDS_LIB mstr_standard
J 2
(-3300 4500);
DISPLAY 0.787234 (-3300 4500);
PAINT MONO (-3300 4500);
DISPLAY INVISIBLE (-3300 4500);
FORCEPROP 1 LAST BODY_TYPE PLUMBING
J 0
(-3300 4450);
DISPLAY 1.234043 (-3300 4450);
PAINT GREEN (-3300 4450);
DISPLAY INVISIBLE (-3300 4450);
FORCEPROP 1 LAST HDL_TAP TRUE
J 0
(-2975 4375);
DISPLAY 1.234043 (-2975 4375);
PAINT GREEN (-2975 4375);
DISPLAY INVISIBLE (-2975 4375);
FORCEPROP 1 LAST PATH I119
J 0
(-3300 4500);
DISPLAY 0.936170 (-3300 4500);
PAINT GREEN (-3300 4500);
DISPLAY INVISIBLE (-3300 4500);
FORCEADD TAP..6
R 2
(650 4750);
FORCEPROP 3 LASTPIN (600 4750) SIG_NAME M_J_DQS_DP<13>
J 0
(610 4760);
DISPLAY 0.659574 (610 4760);
PAINT MONO (610 4760);
DISPLAY INVISIBLE (610 4760);
FORCEPROP 1 LASTPIN (600 4750) BN 13
J 2
(650 4760);
DISPLAY 0.617021 (650 4760);
PAINT PINK (650 4760);
FORCEPROP 2 LAST CDS_LIB mstr_standard
J 0
(650 4750);
DISPLAY 0.787234 (650 4750);
PAINT MONO (650 4750);
DISPLAY INVISIBLE (650 4750);
FORCEPROP 1 LAST BODY_TYPE PLUMBING
J 2
(650 4700);
DISPLAY 1.234043 (650 4700);
PAINT GREEN (650 4700);
DISPLAY INVISIBLE (650 4700);
FORCEPROP 1 LAST HDL_TAP TRUE
J 2
(325 4625);
DISPLAY 1.234043 (325 4625);
PAINT GREEN (325 4625);
DISPLAY INVISIBLE (325 4625);
FORCEPROP 1 LAST PATH I12
J 2
(650 4750);
DISPLAY 0.936170 (650 4750);
PAINT GREEN (650 4750);
DISPLAY INVISIBLE (650 4750);
FORCEADD TAP..6
(-3300 4450);
FORCEPROP 3 LASTPIN (-3250 4450) SIG_NAME M_J_MA<10>
J 0
(-3240 4460);
DISPLAY 0.659574 (-3240 4460);
PAINT MONO (-3240 4460);
DISPLAY INVISIBLE (-3240 4460);
FORCEPROP 1 LASTPIN (-3250 4450) BN 10
J 0
(-3300 4460);
DISPLAY 0.617021 (-3300 4460);
PAINT PINK (-3300 4460);
FORCEPROP 2 LAST CDS_LIB mstr_standard
J 2
(-3300 4450);
DISPLAY 0.787234 (-3300 4450);
PAINT MONO (-3300 4450);
DISPLAY INVISIBLE (-3300 4450);
FORCEPROP 1 LAST BODY_TYPE PLUMBING
J 0
(-3300 4400);
DISPLAY 1.234043 (-3300 4400);
PAINT GREEN (-3300 4400);
DISPLAY INVISIBLE (-3300 4400);
FORCEPROP 1 LAST HDL_TAP TRUE
J 0
(-2975 4325);
DISPLAY 1.234043 (-2975 4325);
PAINT GREEN (-2975 4325);
DISPLAY INVISIBLE (-2975 4325);
FORCEPROP 1 LAST PATH I120
J 0
(-3300 4450);
DISPLAY 0.936170 (-3300 4450);
PAINT GREEN (-3300 4450);
DISPLAY INVISIBLE (-3300 4450);
FORCEADD TAP..6
(-3300 4400);
FORCEPROP 3 LASTPIN (-3250 4400) SIG_NAME M_J_MA<9>
J 0
(-3240 4410);
DISPLAY 0.659574 (-3240 4410);
PAINT MONO (-3240 4410);
DISPLAY INVISIBLE (-3240 4410);
FORCEPROP 1 LASTPIN (-3250 4400) BN 9
J 0
(-3300 4410);
DISPLAY 0.617021 (-3300 4410);
PAINT PINK (-3300 4410);
FORCEPROP 2 LAST CDS_LIB mstr_standard
J 2
(-3300 4400);
DISPLAY 0.787234 (-3300 4400);
PAINT MONO (-3300 4400);
DISPLAY INVISIBLE (-3300 4400);
FORCEPROP 1 LAST BODY_TYPE PLUMBING
J 0
(-3300 4350);
DISPLAY 1.234043 (-3300 4350);
PAINT GREEN (-3300 4350);
DISPLAY INVISIBLE (-3300 4350);
FORCEPROP 1 LAST HDL_TAP TRUE
J 0
(-2975 4275);
DISPLAY 1.234043 (-2975 4275);
PAINT GREEN (-2975 4275);
DISPLAY INVISIBLE (-2975 4275);
FORCEPROP 1 LAST PATH I121
J 0
(-3300 4400);
DISPLAY 0.936170 (-3300 4400);
PAINT GREEN (-3300 4400);
DISPLAY INVISIBLE (-3300 4400);
FORCEADD TAP..6
(-3300 4350);
FORCEPROP 3 LASTPIN (-3250 4350) SIG_NAME M_J_MA<8>
J 0
(-3240 4360);
DISPLAY 0.659574 (-3240 4360);
PAINT MONO (-3240 4360);
DISPLAY INVISIBLE (-3240 4360);
FORCEPROP 1 LASTPIN (-3250 4350) BN 8
J 0
(-3300 4360);
DISPLAY 0.617021 (-3300 4360);
PAINT PINK (-3300 4360);
FORCEPROP 2 LAST CDS_LIB mstr_standard
J 2
(-3300 4350);
DISPLAY 0.787234 (-3300 4350);
PAINT MONO (-3300 4350);
DISPLAY INVISIBLE (-3300 4350);
FORCEPROP 1 LAST BODY_TYPE PLUMBING
J 0
(-3300 4300);
DISPLAY 1.234043 (-3300 4300);
PAINT GREEN (-3300 4300);
DISPLAY INVISIBLE (-3300 4300);
FORCEPROP 1 LAST HDL_TAP TRUE
J 0
(-2975 4225);
DISPLAY 1.234043 (-2975 4225);
PAINT GREEN (-2975 4225);
DISPLAY INVISIBLE (-2975 4225);
FORCEPROP 1 LAST PATH I122
J 0
(-3300 4350);
DISPLAY 0.936170 (-3300 4350);
PAINT GREEN (-3300 4350);
DISPLAY INVISIBLE (-3300 4350);
FORCEADD TAP..6
(-3300 4300);
FORCEPROP 3 LASTPIN (-3250 4300) SIG_NAME M_J_MA<7>
J 0
(-3240 4310);
DISPLAY 0.659574 (-3240 4310);
PAINT MONO (-3240 4310);
DISPLAY INVISIBLE (-3240 4310);
FORCEPROP 1 LASTPIN (-3250 4300) BN 7
J 0
(-3300 4310);
DISPLAY 0.617021 (-3300 4310);
PAINT PINK (-3300 4310);
FORCEPROP 2 LAST CDS_LIB mstr_standard
J 2
(-3300 4300);
DISPLAY 0.787234 (-3300 4300);
PAINT MONO (-3300 4300);
DISPLAY INVISIBLE (-3300 4300);
FORCEPROP 1 LAST BODY_TYPE PLUMBING
J 0
(-3300 4250);
DISPLAY 1.234043 (-3300 4250);
PAINT GREEN (-3300 4250);
DISPLAY INVISIBLE (-3300 4250);
FORCEPROP 1 LAST HDL_TAP TRUE
J 0
(-2975 4175);
DISPLAY 1.234043 (-2975 4175);
PAINT GREEN (-2975 4175);
DISPLAY INVISIBLE (-2975 4175);
FORCEPROP 1 LAST PATH I123
J 0
(-3300 4300);
DISPLAY 0.936170 (-3300 4300);
PAINT GREEN (-3300 4300);
DISPLAY INVISIBLE (-3300 4300);
FORCEADD TAP..6
(-3300 4250);
FORCEPROP 3 LASTPIN (-3250 4250) SIG_NAME M_J_MA<6>
J 0
(-3240 4260);
DISPLAY 0.659574 (-3240 4260);
PAINT MONO (-3240 4260);
DISPLAY INVISIBLE (-3240 4260);
FORCEPROP 1 LASTPIN (-3250 4250) BN 6
J 0
(-3300 4260);
DISPLAY 0.617021 (-3300 4260);
PAINT PINK (-3300 4260);
FORCEPROP 2 LAST CDS_LIB mstr_standard
J 2
(-3300 4250);
DISPLAY 0.787234 (-3300 4250);
PAINT MONO (-3300 4250);
DISPLAY INVISIBLE (-3300 4250);
FORCEPROP 1 LAST BODY_TYPE PLUMBING
J 0
(-3300 4200);
DISPLAY 1.234043 (-3300 4200);
PAINT GREEN (-3300 4200);
DISPLAY INVISIBLE (-3300 4200);
FORCEPROP 1 LAST HDL_TAP TRUE
J 0
(-2975 4125);
DISPLAY 1.234043 (-2975 4125);
PAINT GREEN (-2975 4125);
DISPLAY INVISIBLE (-2975 4125);
FORCEPROP 1 LAST PATH I124
J 0
(-3300 4250);
DISPLAY 0.936170 (-3300 4250);
PAINT GREEN (-3300 4250);
DISPLAY INVISIBLE (-3300 4250);
FORCEADD TAP..6
(-3300 4200);
FORCEPROP 3 LASTPIN (-3250 4200) SIG_NAME M_J_MA<5>
J 0
(-3240 4210);
DISPLAY 0.659574 (-3240 4210);
PAINT MONO (-3240 4210);
DISPLAY INVISIBLE (-3240 4210);
FORCEPROP 1 LASTPIN (-3250 4200) BN 5
J 0
(-3300 4210);
DISPLAY 0.617021 (-3300 4210);
PAINT PINK (-3300 4210);
FORCEPROP 2 LAST CDS_LIB mstr_standard
J 2
(-3300 4200);
DISPLAY 0.787234 (-3300 4200);
PAINT MONO (-3300 4200);
DISPLAY INVISIBLE (-3300 4200);
FORCEPROP 1 LAST BODY_TYPE PLUMBING
J 0
(-3300 4150);
DISPLAY 1.234043 (-3300 4150);
PAINT GREEN (-3300 4150);
DISPLAY INVISIBLE (-3300 4150);
FORCEPROP 1 LAST HDL_TAP TRUE
J 0
(-2975 4075);
DISPLAY 1.234043 (-2975 4075);
PAINT GREEN (-2975 4075);
DISPLAY INVISIBLE (-2975 4075);
FORCEPROP 1 LAST PATH I125
J 0
(-3300 4200);
DISPLAY 0.936170 (-3300 4200);
PAINT GREEN (-3300 4200);
DISPLAY INVISIBLE (-3300 4200);
FORCEADD TAP..6
(-3300 4150);
FORCEPROP 3 LASTPIN (-3250 4150) SIG_NAME M_J_MA<4>
J 0
(-3240 4160);
DISPLAY 0.659574 (-3240 4160);
PAINT MONO (-3240 4160);
DISPLAY INVISIBLE (-3240 4160);
FORCEPROP 1 LASTPIN (-3250 4150) BN 4
J 0
(-3300 4160);
DISPLAY 0.617021 (-3300 4160);
PAINT PINK (-3300 4160);
FORCEPROP 2 LAST CDS_LIB mstr_standard
J 2
(-3300 4150);
DISPLAY 0.787234 (-3300 4150);
PAINT MONO (-3300 4150);
DISPLAY INVISIBLE (-3300 4150);
FORCEPROP 1 LAST BODY_TYPE PLUMBING
J 0
(-3300 4100);
DISPLAY 1.234043 (-3300 4100);
PAINT GREEN (-3300 4100);
DISPLAY INVISIBLE (-3300 4100);
FORCEPROP 1 LAST HDL_TAP TRUE
J 0
(-2975 4025);
DISPLAY 1.234043 (-2975 4025);
PAINT GREEN (-2975 4025);
DISPLAY INVISIBLE (-2975 4025);
FORCEPROP 1 LAST PATH I126
J 0
(-3300 4150);
DISPLAY 0.936170 (-3300 4150);
PAINT GREEN (-3300 4150);
DISPLAY INVISIBLE (-3300 4150);
FORCEADD TAP..6
(-3300 4100);
FORCEPROP 3 LASTPIN (-3250 4100) SIG_NAME M_J_MA<3>
J 0
(-3240 4110);
DISPLAY 0.659574 (-3240 4110);
PAINT MONO (-3240 4110);
DISPLAY INVISIBLE (-3240 4110);
FORCEPROP 1 LASTPIN (-3250 4100) BN 3
J 0
(-3300 4110);
DISPLAY 0.617021 (-3300 4110);
PAINT PINK (-3300 4110);
FORCEPROP 2 LAST CDS_LIB mstr_standard
J 2
(-3300 4100);
DISPLAY 0.787234 (-3300 4100);
PAINT MONO (-3300 4100);
DISPLAY INVISIBLE (-3300 4100);
FORCEPROP 1 LAST BODY_TYPE PLUMBING
J 0
(-3300 4050);
DISPLAY 1.234043 (-3300 4050);
PAINT GREEN (-3300 4050);
DISPLAY INVISIBLE (-3300 4050);
FORCEPROP 1 LAST HDL_TAP TRUE
J 0
(-2975 3975);
DISPLAY 1.234043 (-2975 3975);
PAINT GREEN (-2975 3975);
DISPLAY INVISIBLE (-2975 3975);
FORCEPROP 1 LAST PATH I127
J 0
(-3300 4100);
DISPLAY 0.936170 (-3300 4100);
PAINT GREEN (-3300 4100);
DISPLAY INVISIBLE (-3300 4100);
FORCEADD TAP..6
(-3300 4050);
FORCEPROP 3 LASTPIN (-3250 4050) SIG_NAME M_J_MA<2>
J 0
(-3240 4060);
DISPLAY 0.659574 (-3240 4060);
PAINT MONO (-3240 4060);
DISPLAY INVISIBLE (-3240 4060);
FORCEPROP 1 LASTPIN (-3250 4050) BN 2
J 0
(-3300 4060);
DISPLAY 0.617021 (-3300 4060);
PAINT PINK (-3300 4060);
FORCEPROP 2 LAST CDS_LIB mstr_standard
J 2
(-3300 4050);
DISPLAY 0.787234 (-3300 4050);
PAINT MONO (-3300 4050);
DISPLAY INVISIBLE (-3300 4050);
FORCEPROP 1 LAST BODY_TYPE PLUMBING
J 0
(-3300 4000);
DISPLAY 1.234043 (-3300 4000);
PAINT GREEN (-3300 4000);
DISPLAY INVISIBLE (-3300 4000);
FORCEPROP 1 LAST HDL_TAP TRUE
J 0
(-2975 3925);
DISPLAY 1.234043 (-2975 3925);
PAINT GREEN (-2975 3925);
DISPLAY INVISIBLE (-2975 3925);
FORCEPROP 1 LAST PATH I128
J 0
(-3300 4050);
DISPLAY 0.936170 (-3300 4050);
PAINT GREEN (-3300 4050);
DISPLAY INVISIBLE (-3300 4050);
FORCEADD TAP..6
(-3300 4000);
FORCEPROP 3 LASTPIN (-3250 4000) SIG_NAME M_J_MA<1>
J 0
(-3240 4010);
DISPLAY 0.659574 (-3240 4010);
PAINT MONO (-3240 4010);
DISPLAY INVISIBLE (-3240 4010);
FORCEPROP 1 LASTPIN (-3250 4000) BN 1
J 0
(-3300 4010);
DISPLAY 0.617021 (-3300 4010);
PAINT PINK (-3300 4010);
FORCEPROP 2 LAST CDS_LIB mstr_standard
J 2
(-3300 4000);
DISPLAY 0.787234 (-3300 4000);
PAINT MONO (-3300 4000);
DISPLAY INVISIBLE (-3300 4000);
FORCEPROP 1 LAST BODY_TYPE PLUMBING
J 0
(-3300 3950);
DISPLAY 1.234043 (-3300 3950);
PAINT GREEN (-3300 3950);
DISPLAY INVISIBLE (-3300 3950);
FORCEPROP 1 LAST HDL_TAP TRUE
J 0
(-2975 3875);
DISPLAY 1.234043 (-2975 3875);
PAINT GREEN (-2975 3875);
DISPLAY INVISIBLE (-2975 3875);
FORCEPROP 1 LAST PATH I129
J 0
(-3300 4000);
DISPLAY 0.936170 (-3300 4000);
PAINT GREEN (-3300 4000);
DISPLAY INVISIBLE (-3300 4000);
FORCEADD TAP..6
R 2
(650 4850);
FORCEPROP 3 LASTPIN (600 4850) SIG_NAME M_J_DQS_DP<14>
J 0
(610 4860);
DISPLAY 0.659574 (610 4860);
PAINT MONO (610 4860);
DISPLAY INVISIBLE (610 4860);
FORCEPROP 1 LASTPIN (600 4850) BN 14
J 2
(650 4860);
DISPLAY 0.617021 (650 4860);
PAINT PINK (650 4860);
FORCEPROP 2 LAST CDS_LIB mstr_standard
J 0
(650 4850);
DISPLAY 0.787234 (650 4850);
PAINT MONO (650 4850);
DISPLAY INVISIBLE (650 4850);
FORCEPROP 1 LAST BODY_TYPE PLUMBING
J 2
(650 4800);
DISPLAY 1.234043 (650 4800);
PAINT GREEN (650 4800);
DISPLAY INVISIBLE (650 4800);
FORCEPROP 1 LAST HDL_TAP TRUE
J 2
(325 4725);
DISPLAY 1.234043 (325 4725);
PAINT GREEN (325 4725);
DISPLAY INVISIBLE (325 4725);
FORCEPROP 1 LAST PATH I13
J 2
(650 4850);
DISPLAY 0.936170 (650 4850);
PAINT GREEN (650 4850);
DISPLAY INVISIBLE (650 4850);
FORCEADD TAP..6
(-3300 3950);
FORCEPROP 3 LASTPIN (-3250 3950) SIG_NAME M_J_MA<0>
J 0
(-3240 3960);
DISPLAY 0.659574 (-3240 3960);
PAINT MONO (-3240 3960);
DISPLAY INVISIBLE (-3240 3960);
FORCEPROP 1 LASTPIN (-3250 3950) BN 0
J 0
(-3300 3960);
DISPLAY 0.617021 (-3300 3960);
PAINT PINK (-3300 3960);
FORCEPROP 2 LAST CDS_LIB mstr_standard
J 2
(-3300 3950);
DISPLAY 0.787234 (-3300 3950);
PAINT MONO (-3300 3950);
DISPLAY INVISIBLE (-3300 3950);
FORCEPROP 1 LAST BODY_TYPE PLUMBING
J 0
(-3300 3900);
DISPLAY 1.234043 (-3300 3900);
PAINT GREEN (-3300 3900);
DISPLAY INVISIBLE (-3300 3900);
FORCEPROP 1 LAST HDL_TAP TRUE
J 0
(-2975 3825);
DISPLAY 1.234043 (-2975 3825);
PAINT GREEN (-2975 3825);
DISPLAY INVISIBLE (-2975 3825);
FORCEPROP 1 LAST PATH I130
J 0
(-3300 3950);
DISPLAY 0.936170 (-3300 3950);
PAINT GREEN (-3300 3950);
DISPLAY INVISIBLE (-3300 3950);
FORCEADD TAP..6
(-3300 3850);
FORCEPROP 3 LASTPIN (-3250 3850) SIG_NAME M_J_BA<1>
J 0
(-3240 3860);
DISPLAY 0.659574 (-3240 3860);
PAINT MONO (-3240 3860);
DISPLAY INVISIBLE (-3240 3860);
FORCEPROP 1 LASTPIN (-3250 3850) BN 1
J 0
(-3300 3860);
DISPLAY 0.617021 (-3300 3860);
PAINT PINK (-3300 3860);
FORCEPROP 2 LAST CDS_LIB mstr_standard
J 0
(-3300 3850);
DISPLAY 0.787234 (-3300 3850);
PAINT MONO (-3300 3850);
DISPLAY INVISIBLE (-3300 3850);
FORCEPROP 1 LAST BODY_TYPE PLUMBING
J 0
(-3300 3800);
DISPLAY 1.234043 (-3300 3800);
PAINT GREEN (-3300 3800);
DISPLAY INVISIBLE (-3300 3800);
FORCEPROP 1 LAST HDL_TAP TRUE
J 0
(-2975 3725);
DISPLAY 1.234043 (-2975 3725);
PAINT GREEN (-2975 3725);
DISPLAY INVISIBLE (-2975 3725);
FORCEPROP 1 LAST PATH I131
J 0
(-3300 3850);
DISPLAY 0.936170 (-3300 3850);
PAINT GREEN (-3300 3850);
DISPLAY INVISIBLE (-3300 3850);
FORCEADD TAP..6
(-3300 3800);
FORCEPROP 3 LASTPIN (-3250 3800) SIG_NAME M_J_BA<0>
J 0
(-3240 3810);
DISPLAY 0.659574 (-3240 3810);
PAINT MONO (-3240 3810);
DISPLAY INVISIBLE (-3240 3810);
FORCEPROP 1 LASTPIN (-3250 3800) BN 0
J 0
(-3300 3810);
DISPLAY 0.617021 (-3300 3810);
PAINT PINK (-3300 3810);
FORCEPROP 2 LAST CDS_LIB mstr_standard
J 0
(-3300 3800);
DISPLAY 0.787234 (-3300 3800);
PAINT MONO (-3300 3800);
DISPLAY INVISIBLE (-3300 3800);
FORCEPROP 1 LAST BODY_TYPE PLUMBING
J 0
(-3300 3750);
DISPLAY 1.234043 (-3300 3750);
PAINT GREEN (-3300 3750);
DISPLAY INVISIBLE (-3300 3750);
FORCEPROP 1 LAST HDL_TAP TRUE
J 0
(-2975 3675);
DISPLAY 1.234043 (-2975 3675);
PAINT GREEN (-2975 3675);
DISPLAY INVISIBLE (-2975 3675);
FORCEPROP 1 LAST PATH I132
J 0
(-3300 3800);
DISPLAY 0.936170 (-3300 3800);
PAINT GREEN (-3300 3800);
DISPLAY INVISIBLE (-3300 3800);
FORCEADD OFFPAGE..1
(-3950 3900);
FORCEPROP 2 LAST $XR0 59 
J 0
(-4171 3900);
DISPLAY 0.638298 (-4171 3900);
PAINT MONO (-4171 3900);
FORCEPROP 2 LAST $XR1 82 
J 0
(-4261 3900);
DISPLAY 0.638298 (-4261 3900);
PAINT MONO (-4261 3900);
FORCEPROP 2 LAST CDS_LIB mstr_standard
J 0
(-3950 3900);
DISPLAY 0.787234 (-3950 3900);
PAINT MONO (-3950 3900);
DISPLAY INVISIBLE (-3950 3900);
FORCEPROP 1 LAST OFFPAGE TRUE
J 0
(-3625 3775);
DISPLAY 0.936170 (-3625 3775);
PAINT GREEN (-3625 3775);
DISPLAY INVISIBLE (-3625 3775);
FORCEPROP 1 LAST COMMENT_BODY TRUE
J 0
(-3825 3800);
DISPLAY 0.936170 (-3825 3800);
PAINT GREEN (-3825 3800);
DISPLAY INVISIBLE (-3825 3800);
FORCEPROP 2 LAST PATH I133
J 0
(-3900 3975);
DISPLAY 0.787234 (-3900 3975);
PAINT MONO (-3900 3975);
DISPLAY INVISIBLE (-3900 3975);
FORCEADD TAP..6
(-3300 3750);
FORCEPROP 3 LASTPIN (-3250 3750) SIG_NAME M_J_BG<1>
J 0
(-3240 3760);
DISPLAY 0.659574 (-3240 3760);
PAINT MONO (-3240 3760);
DISPLAY INVISIBLE (-3240 3760);
FORCEPROP 1 LASTPIN (-3250 3750) BN 1
J 0
(-3300 3760);
DISPLAY 0.617021 (-3300 3760);
PAINT PINK (-3300 3760);
FORCEPROP 2 LAST CDS_LIB mstr_standard
J 0
(-3300 3750);
DISPLAY 0.787234 (-3300 3750);
PAINT MONO (-3300 3750);
DISPLAY INVISIBLE (-3300 3750);
FORCEPROP 1 LAST BODY_TYPE PLUMBING
J 0
(-3300 3700);
DISPLAY 1.234043 (-3300 3700);
PAINT GREEN (-3300 3700);
DISPLAY INVISIBLE (-3300 3700);
FORCEPROP 1 LAST HDL_TAP TRUE
J 0
(-2975 3625);
DISPLAY 1.234043 (-2975 3625);
PAINT GREEN (-2975 3625);
DISPLAY INVISIBLE (-2975 3625);
FORCEPROP 1 LAST PATH I134
J 0
(-3300 3750);
DISPLAY 0.936170 (-3300 3750);
PAINT GREEN (-3300 3750);
DISPLAY INVISIBLE (-3300 3750);
FORCEADD TAP..6
(-3300 3700);
FORCEPROP 3 LASTPIN (-3250 3700) SIG_NAME M_J_BG<0>
J 0
(-3240 3710);
DISPLAY 0.659574 (-3240 3710);
PAINT MONO (-3240 3710);
DISPLAY INVISIBLE (-3240 3710);
FORCEPROP 1 LASTPIN (-3250 3700) BN 0
J 0
(-3300 3710);
DISPLAY 0.617021 (-3300 3710);
PAINT PINK (-3300 3710);
FORCEPROP 2 LAST CDS_LIB mstr_standard
J 0
(-3300 3700);
DISPLAY 0.787234 (-3300 3700);
PAINT MONO (-3300 3700);
DISPLAY INVISIBLE (-3300 3700);
FORCEPROP 1 LAST BODY_TYPE PLUMBING
J 0
(-3300 3650);
DISPLAY 1.234043 (-3300 3650);
PAINT GREEN (-3300 3650);
DISPLAY INVISIBLE (-3300 3650);
FORCEPROP 1 LAST HDL_TAP TRUE
J 0
(-2975 3575);
DISPLAY 1.234043 (-2975 3575);
PAINT GREEN (-2975 3575);
DISPLAY INVISIBLE (-2975 3575);
FORCEPROP 1 LAST PATH I135
J 0
(-3300 3700);
DISPLAY 0.936170 (-3300 3700);
PAINT GREEN (-3300 3700);
DISPLAY INVISIBLE (-3300 3700);
FORCEADD OFFPAGE..1
(-3950 3400);
FORCEPROP 2 LAST $XR0 59 
J 0
(-4171 3400);
DISPLAY 0.638298 (-4171 3400);
PAINT MONO (-4171 3400);
FORCEPROP 2 LAST $XR1 82 
J 0
(-4261 3400);
DISPLAY 0.638298 (-4261 3400);
PAINT MONO (-4261 3400);
FORCEPROP 2 LAST CDS_LIB mstr_standard
J 0
(-3950 3400);
DISPLAY 0.787234 (-3950 3400);
PAINT MONO (-3950 3400);
DISPLAY INVISIBLE (-3950 3400);
FORCEPROP 1 LAST OFFPAGE TRUE
J 0
(-3625 3275);
DISPLAY 0.936170 (-3625 3275);
PAINT GREEN (-3625 3275);
DISPLAY INVISIBLE (-3625 3275);
FORCEPROP 1 LAST COMMENT_BODY TRUE
J 0
(-3825 3300);
DISPLAY 0.936170 (-3825 3300);
PAINT GREEN (-3825 3300);
DISPLAY INVISIBLE (-3825 3300);
FORCEPROP 2 LAST PATH I136
J 0
(-3900 3475);
DISPLAY 0.787234 (-3900 3475);
PAINT MONO (-3900 3475);
DISPLAY INVISIBLE (-3900 3475);
FORCEADD TAP..6
(-3300 2750);
FORCEPROP 3 LASTPIN (-3250 2750) SIG_NAME M_J_ECC<6>
J 0
(-3240 2760);
DISPLAY 0.659574 (-3240 2760);
PAINT MONO (-3240 2760);
DISPLAY INVISIBLE (-3240 2760);
FORCEPROP 1 LASTPIN (-3250 2750) BN 6
J 0
(-3300 2760);
DISPLAY 0.617021 (-3300 2760);
PAINT PINK (-3300 2760);
FORCEPROP 2 LAST CDS_LIB mstr_standard
J 0
(-3300 2750);
DISPLAY 0.787234 (-3300 2750);
PAINT MONO (-3300 2750);
DISPLAY INVISIBLE (-3300 2750);
FORCEPROP 1 LAST BODY_TYPE PLUMBING
J 0
(-3300 2700);
DISPLAY 1.234043 (-3300 2700);
PAINT GREEN (-3300 2700);
DISPLAY INVISIBLE (-3300 2700);
FORCEPROP 1 LAST HDL_TAP TRUE
J 0
(-2975 2625);
DISPLAY 1.234043 (-2975 2625);
PAINT GREEN (-2975 2625);
DISPLAY INVISIBLE (-2975 2625);
FORCEPROP 1 LAST PATH I137
J 0
(-3300 2750);
DISPLAY 0.936170 (-3300 2750);
PAINT GREEN (-3300 2750);
DISPLAY INVISIBLE (-3300 2750);
FORCEADD OFFPAGE..1
(-3950 3800);
FORCEPROP 2 LAST $XR0 59 
J 0
(-4171 3800);
DISPLAY 0.638298 (-4171 3800);
PAINT MONO (-4171 3800);
FORCEPROP 2 LAST $XR1 82 
J 0
(-4261 3800);
DISPLAY 0.638298 (-4261 3800);
PAINT MONO (-4261 3800);
FORCEPROP 2 LAST CDS_LIB mstr_standard
J 0
(-3950 3800);
DISPLAY 0.787234 (-3950 3800);
PAINT MONO (-3950 3800);
DISPLAY INVISIBLE (-3950 3800);
FORCEPROP 1 LAST OFFPAGE TRUE
J 0
(-3625 3675);
DISPLAY 0.936170 (-3625 3675);
PAINT GREEN (-3625 3675);
DISPLAY INVISIBLE (-3625 3675);
FORCEPROP 1 LAST COMMENT_BODY TRUE
J 0
(-3825 3700);
DISPLAY 0.936170 (-3825 3700);
PAINT GREEN (-3825 3700);
DISPLAY INVISIBLE (-3825 3700);
FORCEPROP 2 LAST PATH I138
J 0
(-3900 3875);
DISPLAY 0.787234 (-3900 3875);
PAINT MONO (-3900 3875);
DISPLAY INVISIBLE (-3900 3875);
FORCEADD OFFPAGE..6
(-3950 2800);
FORCEPROP 2 LAST $XR0 59 
J 0
(-4229 2800);
DISPLAY 0.638298 (-4229 2800);
PAINT MONO (-4229 2800);
FORCEPROP 2 LAST $XR1 82 
J 0
(-4319 2800);
DISPLAY 0.638298 (-4319 2800);
PAINT MONO (-4319 2800);
FORCEPROP 2 LAST CDS_LIB mstr_standard
J 0
(-3950 2800);
DISPLAY 0.787234 (-3950 2800);
PAINT MONO (-3950 2800);
DISPLAY INVISIBLE (-3950 2800);
FORCEPROP 1 LAST OFFPAGE TRUE
J 0
(-3625 2675);
DISPLAY 0.936170 (-3625 2675);
PAINT GREEN (-3625 2675);
DISPLAY INVISIBLE (-3625 2675);
FORCEPROP 1 LAST COMMENT_BODY TRUE
J 0
(-3850 2725);
DISPLAY 0.936170 (-3850 2725);
PAINT GREEN (-3850 2725);
DISPLAY INVISIBLE (-3850 2725);
FORCEPROP 2 LAST PATH I139
J 0
(-3900 2875);
DISPLAY 0.787234 (-3900 2875);
PAINT MONO (-3900 2875);
DISPLAY INVISIBLE (-3900 2875);
FORCEADD TAP..6
R 2
(650 4950);
FORCEPROP 3 LASTPIN (600 4950) SIG_NAME M_J_DQS_DP<15>
J 0
(610 4960);
DISPLAY 0.659574 (610 4960);
PAINT MONO (610 4960);
DISPLAY INVISIBLE (610 4960);
FORCEPROP 1 LASTPIN (600 4950) BN 15
J 2
(650 4960);
DISPLAY 0.617021 (650 4960);
PAINT PINK (650 4960);
FORCEPROP 2 LAST CDS_LIB mstr_standard
J 0
(650 4950);
DISPLAY 0.787234 (650 4950);
PAINT MONO (650 4950);
DISPLAY INVISIBLE (650 4950);
FORCEPROP 1 LAST BODY_TYPE PLUMBING
J 2
(650 4900);
DISPLAY 1.234043 (650 4900);
PAINT GREEN (650 4900);
DISPLAY INVISIBLE (650 4900);
FORCEPROP 1 LAST HDL_TAP TRUE
J 2
(325 4825);
DISPLAY 1.234043 (325 4825);
PAINT GREEN (325 4825);
DISPLAY INVISIBLE (325 4825);
FORCEPROP 1 LAST PATH I14
J 2
(650 4950);
DISPLAY 0.936170 (650 4950);
PAINT GREEN (650 4950);
DISPLAY INVISIBLE (650 4950);
FORCEADD TAP..6
(-3300 2700);
FORCEPROP 3 LASTPIN (-3250 2700) SIG_NAME M_J_ECC<7>
J 0
(-3240 2710);
DISPLAY 0.659574 (-3240 2710);
PAINT MONO (-3240 2710);
DISPLAY INVISIBLE (-3240 2710);
FORCEPROP 1 LASTPIN (-3250 2700) BN 7
J 0
(-3300 2710);
DISPLAY 0.617021 (-3300 2710);
PAINT PINK (-3300 2710);
FORCEPROP 2 LAST CDS_LIB mstr_standard
J 0
(-3300 2700);
DISPLAY 0.787234 (-3300 2700);
PAINT MONO (-3300 2700);
DISPLAY INVISIBLE (-3300 2700);
FORCEPROP 1 LAST BODY_TYPE PLUMBING
J 0
(-3300 2650);
DISPLAY 1.234043 (-3300 2650);
PAINT GREEN (-3300 2650);
DISPLAY INVISIBLE (-3300 2650);
FORCEPROP 1 LAST HDL_TAP TRUE
J 0
(-2975 2575);
DISPLAY 1.234043 (-2975 2575);
PAINT GREEN (-2975 2575);
DISPLAY INVISIBLE (-2975 2575);
FORCEPROP 1 LAST PATH I140
J 0
(-3300 2700);
DISPLAY 0.936170 (-3300 2700);
PAINT GREEN (-3300 2700);
DISPLAY INVISIBLE (-3300 2700);
FORCEADD TAP..6
(-3300 2650);
FORCEPROP 3 LASTPIN (-3250 2650) SIG_NAME M_J_ECC<4>
J 0
(-3240 2660);
DISPLAY 0.659574 (-3240 2660);
PAINT MONO (-3240 2660);
DISPLAY INVISIBLE (-3240 2660);
FORCEPROP 1 LASTPIN (-3250 2650) BN 4
J 0
(-3300 2660);
DISPLAY 0.617021 (-3300 2660);
PAINT PINK (-3300 2660);
FORCEPROP 2 LAST CDS_LIB mstr_standard
J 0
(-3300 2650);
DISPLAY 0.787234 (-3300 2650);
PAINT MONO (-3300 2650);
DISPLAY INVISIBLE (-3300 2650);
FORCEPROP 1 LAST BODY_TYPE PLUMBING
J 0
(-3300 2600);
DISPLAY 1.234043 (-3300 2600);
PAINT GREEN (-3300 2600);
DISPLAY INVISIBLE (-3300 2600);
FORCEPROP 1 LAST HDL_TAP TRUE
J 0
(-2975 2525);
DISPLAY 1.234043 (-2975 2525);
PAINT GREEN (-2975 2525);
DISPLAY INVISIBLE (-2975 2525);
FORCEPROP 1 LAST PATH I141
J 0
(-3300 2650);
DISPLAY 0.936170 (-3300 2650);
PAINT GREEN (-3300 2650);
DISPLAY INVISIBLE (-3300 2650);
FORCEADD TAP..6
(-3300 2600);
FORCEPROP 3 LASTPIN (-3250 2600) SIG_NAME M_J_ECC<5>
J 0
(-3240 2610);
DISPLAY 0.659574 (-3240 2610);
PAINT MONO (-3240 2610);
DISPLAY INVISIBLE (-3240 2610);
FORCEPROP 1 LASTPIN (-3250 2600) BN 5
J 0
(-3300 2610);
DISPLAY 0.617021 (-3300 2610);
PAINT PINK (-3300 2610);
FORCEPROP 2 LAST CDS_LIB mstr_standard
J 0
(-3300 2600);
DISPLAY 0.787234 (-3300 2600);
PAINT MONO (-3300 2600);
DISPLAY INVISIBLE (-3300 2600);
FORCEPROP 1 LAST BODY_TYPE PLUMBING
J 0
(-3300 2550);
DISPLAY 1.234043 (-3300 2550);
PAINT GREEN (-3300 2550);
DISPLAY INVISIBLE (-3300 2550);
FORCEPROP 1 LAST HDL_TAP TRUE
J 0
(-2975 2475);
DISPLAY 1.234043 (-2975 2475);
PAINT GREEN (-2975 2475);
DISPLAY INVISIBLE (-2975 2475);
FORCEPROP 1 LAST PATH I142
J 0
(-3300 2600);
DISPLAY 0.936170 (-3300 2600);
PAINT GREEN (-3300 2600);
DISPLAY INVISIBLE (-3300 2600);
FORCEADD TAP..6
(-3300 2550);
FORCEPROP 3 LASTPIN (-3250 2550) SIG_NAME M_J_ECC<2>
J 0
(-3240 2560);
DISPLAY 0.659574 (-3240 2560);
PAINT MONO (-3240 2560);
DISPLAY INVISIBLE (-3240 2560);
FORCEPROP 1 LASTPIN (-3250 2550) BN 2
J 0
(-3300 2560);
DISPLAY 0.617021 (-3300 2560);
PAINT PINK (-3300 2560);
FORCEPROP 2 LAST CDS_LIB mstr_standard
J 0
(-3300 2550);
DISPLAY 0.787234 (-3300 2550);
PAINT MONO (-3300 2550);
DISPLAY INVISIBLE (-3300 2550);
FORCEPROP 1 LAST BODY_TYPE PLUMBING
J 0
(-3300 2500);
DISPLAY 1.234043 (-3300 2500);
PAINT GREEN (-3300 2500);
DISPLAY INVISIBLE (-3300 2500);
FORCEPROP 1 LAST HDL_TAP TRUE
J 0
(-2975 2425);
DISPLAY 1.234043 (-2975 2425);
PAINT GREEN (-2975 2425);
DISPLAY INVISIBLE (-2975 2425);
FORCEPROP 1 LAST PATH I143
J 0
(-3300 2550);
DISPLAY 0.936170 (-3300 2550);
PAINT GREEN (-3300 2550);
DISPLAY INVISIBLE (-3300 2550);
FORCEADD TAP..6
(-3300 2500);
FORCEPROP 3 LASTPIN (-3250 2500) SIG_NAME M_J_ECC<3>
J 0
(-3240 2510);
DISPLAY 0.659574 (-3240 2510);
PAINT MONO (-3240 2510);
DISPLAY INVISIBLE (-3240 2510);
FORCEPROP 1 LASTPIN (-3250 2500) BN 3
J 0
(-3300 2510);
DISPLAY 0.617021 (-3300 2510);
PAINT PINK (-3300 2510);
FORCEPROP 2 LAST CDS_LIB mstr_standard
J 0
(-3300 2500);
DISPLAY 0.787234 (-3300 2500);
PAINT MONO (-3300 2500);
DISPLAY INVISIBLE (-3300 2500);
FORCEPROP 1 LAST BODY_TYPE PLUMBING
J 0
(-3300 2450);
DISPLAY 1.234043 (-3300 2450);
PAINT GREEN (-3300 2450);
DISPLAY INVISIBLE (-3300 2450);
FORCEPROP 1 LAST HDL_TAP TRUE
J 0
(-2975 2375);
DISPLAY 1.234043 (-2975 2375);
PAINT GREEN (-2975 2375);
DISPLAY INVISIBLE (-2975 2375);
FORCEPROP 1 LAST PATH I144
J 0
(-3300 2500);
DISPLAY 0.936170 (-3300 2500);
PAINT GREEN (-3300 2500);
DISPLAY INVISIBLE (-3300 2500);
FORCEADD TAP..6
(-3300 2400);
FORCEPROP 3 LASTPIN (-3250 2400) SIG_NAME M_J_ECC<1>
J 0
(-3240 2410);
DISPLAY 0.659574 (-3240 2410);
PAINT MONO (-3240 2410);
DISPLAY INVISIBLE (-3240 2410);
FORCEPROP 1 LASTPIN (-3250 2400) BN 1
J 0
(-3300 2410);
DISPLAY 0.617021 (-3300 2410);
PAINT PINK (-3300 2410);
FORCEPROP 2 LAST CDS_LIB mstr_standard
J 0
(-3300 2400);
DISPLAY 0.787234 (-3300 2400);
PAINT MONO (-3300 2400);
DISPLAY INVISIBLE (-3300 2400);
FORCEPROP 1 LAST BODY_TYPE PLUMBING
J 0
(-3300 2350);
DISPLAY 1.234043 (-3300 2350);
PAINT GREEN (-3300 2350);
DISPLAY INVISIBLE (-3300 2350);
FORCEPROP 1 LAST HDL_TAP TRUE
J 0
(-2975 2275);
DISPLAY 1.234043 (-2975 2275);
PAINT GREEN (-2975 2275);
DISPLAY INVISIBLE (-2975 2275);
FORCEPROP 1 LAST PATH I145
J 0
(-3300 2400);
DISPLAY 0.936170 (-3300 2400);
PAINT GREEN (-3300 2400);
DISPLAY INVISIBLE (-3300 2400);
FORCEADD TAP..6
(-3300 2450);
FORCEPROP 3 LASTPIN (-3250 2450) SIG_NAME M_J_ECC<0>
J 0
(-3240 2460);
DISPLAY 0.659574 (-3240 2460);
PAINT MONO (-3240 2460);
DISPLAY INVISIBLE (-3240 2460);
FORCEPROP 1 LASTPIN (-3250 2450) BN 0
J 0
(-3300 2460);
DISPLAY 0.617021 (-3300 2460);
PAINT PINK (-3300 2460);
FORCEPROP 2 LAST CDS_LIB mstr_standard
J 0
(-3300 2450);
DISPLAY 0.787234 (-3300 2450);
PAINT MONO (-3300 2450);
DISPLAY INVISIBLE (-3300 2450);
FORCEPROP 1 LAST BODY_TYPE PLUMBING
J 0
(-3300 2400);
DISPLAY 1.234043 (-3300 2400);
PAINT GREEN (-3300 2400);
DISPLAY INVISIBLE (-3300 2400);
FORCEPROP 1 LAST HDL_TAP TRUE
J 0
(-2975 2325);
DISPLAY 1.234043 (-2975 2325);
PAINT GREEN (-2975 2325);
DISPLAY INVISIBLE (-2975 2325);
FORCEPROP 1 LAST PATH I146
J 0
(-3300 2450);
DISPLAY 0.936170 (-3300 2450);
PAINT GREEN (-3300 2450);
DISPLAY INVISIBLE (-3300 2450);
FORCEADD OFFPAGE..1
(-3950 2750);
FORCEPROP 2 LAST $XR0 59 
J 0
(-4201 2750);
DISPLAY 0.638298 (-4201 2750);
PAINT MONO (-4201 2750);
FORCEPROP 2 LAST $XR1 82 
J 0
(-4291 2750);
DISPLAY 0.638298 (-4291 2750);
PAINT MONO (-4291 2750);
FORCEPROP 2 LAST CDS_LIB mstr_standard
J 0
(-3950 2750);
DISPLAY 0.787234 (-3950 2750);
PAINT MONO (-3950 2750);
DISPLAY INVISIBLE (-3950 2750);
FORCEPROP 1 LAST OFFPAGE TRUE
J 0
(-3625 2625);
DISPLAY 0.936170 (-3625 2625);
PAINT GREEN (-3625 2625);
DISPLAY INVISIBLE (-3625 2625);
FORCEPROP 1 LAST COMMENT_BODY TRUE
J 0
(-3825 2650);
DISPLAY 0.936170 (-3825 2650);
PAINT GREEN (-3825 2650);
DISPLAY INVISIBLE (-3825 2650);
FORCEPROP 2 LAST PATH I147
J 0
(-3900 2825);
DISPLAY 0.787234 (-3900 2825);
PAINT MONO (-3900 2825);
DISPLAY INVISIBLE (-3900 2825);
FORCEADD OFFPAGE..1
(-3950 2700);
FORCEPROP 2 LAST $XR0 55 
J 0
(-4171 2700);
DISPLAY 0.638298 (-4171 2700);
PAINT MONO (-4171 2700);
FORCEPROP 2 LAST $XR1 77 
J 0
(-4261 2700);
DISPLAY 0.638298 (-4261 2700);
PAINT MONO (-4261 2700);
FORCEPROP 2 LAST $XR2 78 
J 0
(-4351 2700);
DISPLAY 0.638298 (-4351 2700);
PAINT MONO (-4351 2700);
FORCEPROP 2 LAST $XR3 79 
J 0
(-4441 2700);
DISPLAY 0.638298 (-4441 2700);
PAINT MONO (-4441 2700);
FORCEPROP 2 LAST $XR4 80 
J 0
(-4531 2700);
DISPLAY 0.638298 (-4531 2700);
PAINT MONO (-4531 2700);
FORCEPROP 2 LAST $XR5 82 
J 0
(-4621 2700);
DISPLAY 0.638298 (-4621 2700);
PAINT MONO (-4621 2700);
FORCEPROP 2 LAST CDS_LIB mstr_standard
J 0
(-3950 2700);
DISPLAY 0.787234 (-3950 2700);
PAINT MONO (-3950 2700);
DISPLAY INVISIBLE (-3950 2700);
FORCEPROP 1 LAST OFFPAGE TRUE
J 0
(-3625 2575);
DISPLAY 0.936170 (-3625 2575);
PAINT GREEN (-3625 2575);
DISPLAY INVISIBLE (-3625 2575);
FORCEPROP 1 LAST COMMENT_BODY TRUE
J 0
(-3825 2600);
DISPLAY 0.936170 (-3825 2600);
PAINT GREEN (-3825 2600);
DISPLAY INVISIBLE (-3825 2600);
FORCEPROP 2 LAST PATH I148
J 0
(-3900 2775);
DISPLAY 0.787234 (-3900 2775);
PAINT MONO (-3900 2775);
DISPLAY INVISIBLE (-3900 2775);
FORCEADD OFFPAGE..1
(-4100 2100);
FORCEPROP 2 LAST $XR0 59 
J 0
(-4381 2100);
DISPLAY 0.638298 (-4381 2100);
PAINT MONO (-4381 2100);
FORCEPROP 2 LAST $XR1 82 
J 0
(-4471 2100);
DISPLAY 0.638298 (-4471 2100);
PAINT MONO (-4471 2100);
FORCEPROP 2 LAST CDS_LIB mstr_standard
J 0
(-4100 2100);
DISPLAY 0.787234 (-4100 2100);
PAINT MONO (-4100 2100);
DISPLAY INVISIBLE (-4100 2100);
FORCEPROP 1 LAST OFFPAGE TRUE
J 0
(-3775 1975);
DISPLAY 0.936170 (-3775 1975);
PAINT GREEN (-3775 1975);
DISPLAY INVISIBLE (-3775 1975);
FORCEPROP 1 LAST COMMENT_BODY TRUE
J 0
(-3975 2000);
DISPLAY 0.936170 (-3975 2000);
PAINT GREEN (-3975 2000);
DISPLAY INVISIBLE (-3975 2000);
FORCEPROP 2 LAST PATH I149
J 0
(-4050 2175);
DISPLAY 0.787234 (-4050 2175);
PAINT MONO (-4050 2175);
DISPLAY INVISIBLE (-4050 2175);
FORCEADD TAP..6
R 2
(650 4650);
FORCEPROP 3 LASTPIN (600 4650) SIG_NAME M_J_DQS_DP<12>
J 0
(610 4660);
DISPLAY 0.659574 (610 4660);
PAINT MONO (610 4660);
DISPLAY INVISIBLE (610 4660);
FORCEPROP 1 LASTPIN (600 4650) BN 12
J 2
(650 4660);
DISPLAY 0.617021 (650 4660);
PAINT PINK (650 4660);
FORCEPROP 2 LAST CDS_LIB mstr_standard
J 0
(650 4650);
DISPLAY 0.787234 (650 4650);
PAINT MONO (650 4650);
DISPLAY INVISIBLE (650 4650);
FORCEPROP 1 LAST BODY_TYPE PLUMBING
J 2
(650 4600);
DISPLAY 1.234043 (650 4600);
PAINT GREEN (650 4600);
DISPLAY INVISIBLE (650 4600);
FORCEPROP 1 LAST HDL_TAP TRUE
J 2
(325 4525);
DISPLAY 1.234043 (325 4525);
PAINT GREEN (325 4525);
DISPLAY INVISIBLE (325 4525);
FORCEPROP 1 LAST PATH I15
J 2
(650 4650);
DISPLAY 0.936170 (650 4650);
PAINT GREEN (650 4650);
DISPLAY INVISIBLE (650 4650);
FORCEADD OFFPAGE..5
(-4125 2150);
FORCEPROP 2 LAST $XR0 82 
J 0
(-4379 2150);
DISPLAY 0.638298 (-4379 2150);
PAINT MONO (-4379 2150);
FORCEPROP 2 LAST $XR1 59 
J 0
(-4469 2150);
DISPLAY 0.638298 (-4469 2150);
PAINT MONO (-4469 2150);
FORCEPROP 2 LAST CDS_LIB mstr_standard
J 0
(-4125 2150);
DISPLAY 0.787234 (-4125 2150);
PAINT MONO (-4125 2150);
DISPLAY INVISIBLE (-4125 2150);
FORCEPROP 1 LAST OFFPAGE TRUE
J 0
(-3800 2025);
DISPLAY 1.404255 (-3800 2025);
PAINT GREEN (-3800 2025);
DISPLAY INVISIBLE (-3800 2025);
FORCEPROP 1 LAST COMMENT_BODY TRUE
J 0
(-4025 2075);
DISPLAY 1.404255 (-4025 2075);
PAINT GREEN (-4025 2075);
DISPLAY INVISIBLE (-4025 2075);
FORCEPROP 2 LAST PATH I150
J 0
(-4075 2225);
DISPLAY 0.787234 (-4075 2225);
PAINT MONO (-4075 2225);
DISPLAY INVISIBLE (-4075 2225);
FORCEADD TAP..6
(-3600 3600);
FORCEPROP 3 LASTPIN (-3550 3600) SIG_NAME M_J_CLK_DP<1>
J 0
(-3540 3610);
DISPLAY 0.659574 (-3540 3610);
PAINT MONO (-3540 3610);
DISPLAY INVISIBLE (-3540 3610);
FORCEPROP 1 LASTPIN (-3550 3600) BN 1
J 0
(-3600 3610);
DISPLAY 0.617021 (-3600 3610);
PAINT PINK (-3600 3610);
FORCEPROP 2 LAST CDS_LIB mstr_standard
J 0
(-3600 3600);
DISPLAY 0.787234 (-3600 3600);
PAINT MONO (-3600 3600);
DISPLAY INVISIBLE (-3600 3600);
FORCEPROP 1 LAST BODY_TYPE PLUMBING
J 0
(-3600 3550);
DISPLAY 1.234043 (-3600 3550);
PAINT GREEN (-3600 3550);
DISPLAY INVISIBLE (-3600 3550);
FORCEPROP 1 LAST HDL_TAP TRUE
J 0
(-3275 3475);
DISPLAY 1.234043 (-3275 3475);
PAINT GREEN (-3275 3475);
DISPLAY INVISIBLE (-3275 3475);
FORCEPROP 1 LAST PATH I152
J 0
(-3600 3600);
DISPLAY 0.936170 (-3600 3600);
PAINT GREEN (-3600 3600);
DISPLAY INVISIBLE (-3600 3600);
FORCEADD TAP..6
(-3600 3500);
FORCEPROP 3 LASTPIN (-3550 3500) SIG_NAME M_J_CLK_DP<0>
J 0
(-3540 3510);
DISPLAY 0.659574 (-3540 3510);
PAINT MONO (-3540 3510);
DISPLAY INVISIBLE (-3540 3510);
FORCEPROP 1 LASTPIN (-3550 3500) BN 0
J 0
(-3600 3510);
DISPLAY 0.617021 (-3600 3510);
PAINT PINK (-3600 3510);
FORCEPROP 2 LAST CDS_LIB mstr_standard
J 0
(-3600 3500);
DISPLAY 0.787234 (-3600 3500);
PAINT MONO (-3600 3500);
DISPLAY INVISIBLE (-3600 3500);
FORCEPROP 1 LAST BODY_TYPE PLUMBING
J 0
(-3600 3450);
DISPLAY 1.234043 (-3600 3450);
PAINT GREEN (-3600 3450);
DISPLAY INVISIBLE (-3600 3450);
FORCEPROP 1 LAST HDL_TAP TRUE
J 0
(-3275 3375);
DISPLAY 1.234043 (-3275 3375);
PAINT GREEN (-3275 3375);
DISPLAY INVISIBLE (-3275 3375);
FORCEPROP 1 LAST PATH I153
J 0
(-3600 3500);
DISPLAY 0.936170 (-3600 3500);
PAINT GREEN (-3600 3500);
DISPLAY INVISIBLE (-3600 3500);
FORCEADD TAP..6
(-3750 3550);
FORCEPROP 3 LASTPIN (-3700 3550) SIG_NAME M_J_CLK_DN<1>
J 0
(-3690 3560);
DISPLAY 0.659574 (-3690 3560);
PAINT MONO (-3690 3560);
DISPLAY INVISIBLE (-3690 3560);
FORCEPROP 1 LASTPIN (-3700 3550) BN 1
J 0
(-3750 3560);
DISPLAY 0.617021 (-3750 3560);
PAINT PINK (-3750 3560);
FORCEPROP 2 LAST CDS_LIB mstr_standard
J 0
(-3750 3550);
DISPLAY 0.787234 (-3750 3550);
PAINT MONO (-3750 3550);
DISPLAY INVISIBLE (-3750 3550);
FORCEPROP 1 LAST BODY_TYPE PLUMBING
J 0
(-3750 3500);
DISPLAY 1.234043 (-3750 3500);
PAINT GREEN (-3750 3500);
DISPLAY INVISIBLE (-3750 3500);
FORCEPROP 1 LAST HDL_TAP TRUE
J 0
(-3425 3425);
DISPLAY 1.234043 (-3425 3425);
PAINT GREEN (-3425 3425);
DISPLAY INVISIBLE (-3425 3425);
FORCEPROP 1 LAST PATH I154
J 0
(-3750 3550);
DISPLAY 0.936170 (-3750 3550);
PAINT GREEN (-3750 3550);
DISPLAY INVISIBLE (-3750 3550);
FORCEADD TAP..6
(-3750 3450);
FORCEPROP 3 LASTPIN (-3700 3450) SIG_NAME M_J_CLK_DN<0>
J 0
(-3690 3460);
DISPLAY 0.659574 (-3690 3460);
PAINT MONO (-3690 3460);
DISPLAY INVISIBLE (-3690 3460);
FORCEPROP 1 LASTPIN (-3700 3450) BN 0
J 0
(-3750 3460);
DISPLAY 0.617021 (-3750 3460);
PAINT PINK (-3750 3460);
FORCEPROP 2 LAST CDS_LIB mstr_standard
J 0
(-3750 3450);
DISPLAY 0.787234 (-3750 3450);
PAINT MONO (-3750 3450);
DISPLAY INVISIBLE (-3750 3450);
FORCEPROP 1 LAST BODY_TYPE PLUMBING
J 0
(-3750 3400);
DISPLAY 1.234043 (-3750 3400);
PAINT GREEN (-3750 3400);
DISPLAY INVISIBLE (-3750 3400);
FORCEPROP 1 LAST HDL_TAP TRUE
J 0
(-3425 3325);
DISPLAY 1.234043 (-3425 3325);
PAINT GREEN (-3425 3325);
DISPLAY INVISIBLE (-3425 3325);
FORCEPROP 1 LAST PATH I155
J 0
(-3750 3450);
DISPLAY 0.936170 (-3750 3450);
PAINT GREEN (-3750 3450);
DISPLAY INVISIBLE (-3750 3450);
FORCEADD OFFPAGE..1
(-4300 3600);
FORCEPROP 2 LAST $XR0 59 
J 0
(-4521 3600);
DISPLAY 0.638298 (-4521 3600);
PAINT MONO (-4521 3600);
FORCEPROP 2 LAST $XR1 82 
J 0
(-4611 3600);
DISPLAY 0.638298 (-4611 3600);
PAINT MONO (-4611 3600);
FORCEPROP 2 LAST CDS_LIB mstr_standard
J 0
(-4300 3600);
DISPLAY 0.787234 (-4300 3600);
PAINT MONO (-4300 3600);
DISPLAY INVISIBLE (-4300 3600);
FORCEPROP 1 LAST OFFPAGE TRUE
J 0
(-3975 3475);
DISPLAY 0.936170 (-3975 3475);
PAINT GREEN (-3975 3475);
DISPLAY INVISIBLE (-3975 3475);
FORCEPROP 1 LAST COMMENT_BODY TRUE
J 0
(-4175 3500);
DISPLAY 0.936170 (-4175 3500);
PAINT GREEN (-4175 3500);
DISPLAY INVISIBLE (-4175 3500);
FORCEPROP 2 LAST PATH I156
J 0
(-4250 3675);
DISPLAY 0.787234 (-4250 3675);
PAINT MONO (-4250 3675);
DISPLAY INVISIBLE (-4250 3675);
FORCEADD OFFPAGE..1
(-4300 3650);
FORCEPROP 2 LAST $XR0 59 
J 0
(-4521 3650);
DISPLAY 0.638298 (-4521 3650);
PAINT MONO (-4521 3650);
FORCEPROP 2 LAST $XR1 82 
J 0
(-4611 3650);
DISPLAY 0.638298 (-4611 3650);
PAINT MONO (-4611 3650);
FORCEPROP 2 LAST CDS_LIB mstr_standard
J 0
(-4300 3650);
DISPLAY 0.787234 (-4300 3650);
PAINT MONO (-4300 3650);
DISPLAY INVISIBLE (-4300 3650);
FORCEPROP 1 LAST OFFPAGE TRUE
J 0
(-3975 3525);
DISPLAY 0.936170 (-3975 3525);
PAINT GREEN (-3975 3525);
DISPLAY INVISIBLE (-3975 3525);
FORCEPROP 1 LAST COMMENT_BODY TRUE
J 0
(-4175 3550);
DISPLAY 0.936170 (-4175 3550);
PAINT GREEN (-4175 3550);
DISPLAY INVISIBLE (-4175 3550);
FORCEPROP 2 LAST PATH I157
J 0
(-4250 3725);
DISPLAY 0.787234 (-4250 3725);
PAINT MONO (-4250 3725);
DISPLAY INVISIBLE (-4250 3725);
FORCEADD TAP..6
(-3300 3300);
FORCEPROP 3 LASTPIN (-3250 3300) SIG_NAME M_J_CS_N<3>
J 0
(-3240 3310);
DISPLAY 0.659574 (-3240 3310);
PAINT MONO (-3240 3310);
DISPLAY INVISIBLE (-3240 3310);
FORCEPROP 1 LASTPIN (-3250 3300) BN 3
J 0
(-3300 3310);
DISPLAY 0.617021 (-3300 3310);
PAINT PINK (-3300 3310);
FORCEPROP 2 LAST CDS_LIB mstr_standard
J 0
(-3300 3300);
DISPLAY 0.787234 (-3300 3300);
PAINT MONO (-3300 3300);
DISPLAY INVISIBLE (-3300 3300);
FORCEPROP 1 LAST BODY_TYPE PLUMBING
J 0
(-3300 3250);
DISPLAY 1.234043 (-3300 3250);
PAINT GREEN (-3300 3250);
DISPLAY INVISIBLE (-3300 3250);
FORCEPROP 1 LAST HDL_TAP TRUE
J 0
(-2975 3175);
DISPLAY 1.234043 (-2975 3175);
PAINT GREEN (-2975 3175);
DISPLAY INVISIBLE (-2975 3175);
FORCEPROP 1 LAST PATH I158
J 0
(-3300 3300);
DISPLAY 0.936170 (-3300 3300);
PAINT GREEN (-3300 3300);
DISPLAY INVISIBLE (-3300 3300);
FORCEADD TAP..6
(-3300 3250);
FORCEPROP 3 LASTPIN (-3250 3250) SIG_NAME M_J_CS_N<2>
J 0
(-3240 3260);
DISPLAY 0.659574 (-3240 3260);
PAINT MONO (-3240 3260);
DISPLAY INVISIBLE (-3240 3260);
FORCEPROP 1 LASTPIN (-3250 3250) BN 2
J 0
(-3300 3260);
DISPLAY 0.617021 (-3300 3260);
PAINT PINK (-3300 3260);
FORCEPROP 2 LAST CDS_LIB mstr_standard
J 0
(-3300 3250);
DISPLAY 0.787234 (-3300 3250);
PAINT MONO (-3300 3250);
DISPLAY INVISIBLE (-3300 3250);
FORCEPROP 1 LAST BODY_TYPE PLUMBING
J 0
(-3300 3200);
DISPLAY 1.234043 (-3300 3200);
PAINT GREEN (-3300 3200);
DISPLAY INVISIBLE (-3300 3200);
FORCEPROP 1 LAST HDL_TAP TRUE
J 0
(-2975 3125);
DISPLAY 1.234043 (-2975 3125);
PAINT GREEN (-2975 3125);
DISPLAY INVISIBLE (-2975 3125);
FORCEPROP 1 LAST PATH I159
J 0
(-3300 3250);
DISPLAY 0.936170 (-3300 3250);
PAINT GREEN (-3300 3250);
DISPLAY INVISIBLE (-3300 3250);
FORCEADD TAP..6
R 2
(650 4550);
FORCEPROP 3 LASTPIN (600 4550) SIG_NAME M_J_DQS_DP<11>
J 0
(610 4560);
DISPLAY 0.659574 (610 4560);
PAINT MONO (610 4560);
DISPLAY INVISIBLE (610 4560);
FORCEPROP 1 LASTPIN (600 4550) BN 11
J 2
(650 4560);
DISPLAY 0.617021 (650 4560);
PAINT PINK (650 4560);
FORCEPROP 2 LAST CDS_LIB mstr_standard
J 0
(650 4550);
DISPLAY 0.787234 (650 4550);
PAINT MONO (650 4550);
DISPLAY INVISIBLE (650 4550);
FORCEPROP 1 LAST BODY_TYPE PLUMBING
J 2
(650 4500);
DISPLAY 1.234043 (650 4500);
PAINT GREEN (650 4500);
DISPLAY INVISIBLE (650 4500);
FORCEPROP 1 LAST HDL_TAP TRUE
J 2
(325 4425);
DISPLAY 1.234043 (325 4425);
PAINT GREEN (325 4425);
DISPLAY INVISIBLE (325 4425);
FORCEPROP 1 LAST PATH I16
J 2
(650 4550);
DISPLAY 0.936170 (650 4550);
PAINT GREEN (650 4550);
DISPLAY INVISIBLE (650 4550);
FORCEADD TAP..6
(-3300 3200);
FORCEPROP 3 LASTPIN (-3250 3200) SIG_NAME M_J_CS_N<1>
J 0
(-3240 3210);
DISPLAY 0.659574 (-3240 3210);
PAINT MONO (-3240 3210);
DISPLAY INVISIBLE (-3240 3210);
FORCEPROP 1 LASTPIN (-3250 3200) BN 1
J 0
(-3300 3210);
DISPLAY 0.617021 (-3300 3210);
PAINT PINK (-3300 3210);
FORCEPROP 2 LAST CDS_LIB mstr_standard
J 0
(-3300 3200);
DISPLAY 0.787234 (-3300 3200);
PAINT MONO (-3300 3200);
DISPLAY INVISIBLE (-3300 3200);
FORCEPROP 1 LAST BODY_TYPE PLUMBING
J 0
(-3300 3150);
DISPLAY 1.234043 (-3300 3150);
PAINT GREEN (-3300 3150);
DISPLAY INVISIBLE (-3300 3150);
FORCEPROP 1 LAST HDL_TAP TRUE
J 0
(-2975 3075);
DISPLAY 1.234043 (-2975 3075);
PAINT GREEN (-2975 3075);
DISPLAY INVISIBLE (-2975 3075);
FORCEPROP 1 LAST PATH I160
J 0
(-3300 3200);
DISPLAY 0.936170 (-3300 3200);
PAINT GREEN (-3300 3200);
DISPLAY INVISIBLE (-3300 3200);
FORCEADD TAP..6
(-3300 3150);
FORCEPROP 3 LASTPIN (-3250 3150) SIG_NAME M_J_CS_N<0>
J 0
(-3240 3160);
DISPLAY 0.659574 (-3240 3160);
PAINT MONO (-3240 3160);
DISPLAY INVISIBLE (-3240 3160);
FORCEPROP 1 LASTPIN (-3250 3150) BN 0
J 0
(-3300 3160);
DISPLAY 0.617021 (-3300 3160);
PAINT PINK (-3300 3160);
FORCEPROP 2 LAST CDS_LIB mstr_standard
J 0
(-3300 3150);
DISPLAY 0.787234 (-3300 3150);
PAINT MONO (-3300 3150);
DISPLAY INVISIBLE (-3300 3150);
FORCEPROP 1 LAST BODY_TYPE PLUMBING
J 0
(-3300 3100);
DISPLAY 1.234043 (-3300 3100);
PAINT GREEN (-3300 3100);
DISPLAY INVISIBLE (-3300 3100);
FORCEPROP 1 LAST HDL_TAP TRUE
J 0
(-2975 3025);
DISPLAY 1.234043 (-2975 3025);
PAINT GREEN (-2975 3025);
DISPLAY INVISIBLE (-2975 3025);
FORCEPROP 1 LAST PATH I161
J 0
(-3300 3150);
DISPLAY 0.936170 (-3300 3150);
PAINT GREEN (-3300 3150);
DISPLAY INVISIBLE (-3300 3150);
FORCEADD TAP..6
(-3300 3050);
FORCEPROP 3 LASTPIN (-3250 3050) SIG_NAME M_J_CKE<1>
J 0
(-3240 3060);
DISPLAY 0.659574 (-3240 3060);
PAINT MONO (-3240 3060);
DISPLAY INVISIBLE (-3240 3060);
FORCEPROP 1 LASTPIN (-3250 3050) BN 1
J 0
(-3300 3060);
DISPLAY 0.617021 (-3300 3060);
PAINT PINK (-3300 3060);
FORCEPROP 2 LAST CDS_LIB mstr_standard
J 0
(-3300 3050);
DISPLAY 0.787234 (-3300 3050);
PAINT MONO (-3300 3050);
DISPLAY INVISIBLE (-3300 3050);
FORCEPROP 1 LAST BODY_TYPE PLUMBING
J 0
(-3300 3000);
DISPLAY 1.234043 (-3300 3000);
PAINT GREEN (-3300 3000);
DISPLAY INVISIBLE (-3300 3000);
FORCEPROP 1 LAST HDL_TAP TRUE
J 0
(-2975 2925);
DISPLAY 1.234043 (-2975 2925);
PAINT GREEN (-2975 2925);
DISPLAY INVISIBLE (-2975 2925);
FORCEPROP 1 LAST PATH I162
J 0
(-3300 3050);
DISPLAY 0.936170 (-3300 3050);
PAINT GREEN (-3300 3050);
DISPLAY INVISIBLE (-3300 3050);
FORCEADD TAP..6
(-3300 3000);
FORCEPROP 3 LASTPIN (-3250 3000) SIG_NAME M_J_CKE<0>
J 0
(-3240 3010);
DISPLAY 0.659574 (-3240 3010);
PAINT MONO (-3240 3010);
DISPLAY INVISIBLE (-3240 3010);
FORCEPROP 1 LASTPIN (-3250 3000) BN 0
J 0
(-3300 3010);
DISPLAY 0.617021 (-3300 3010);
PAINT PINK (-3300 3010);
FORCEPROP 2 LAST CDS_LIB mstr_standard
J 0
(-3300 3000);
DISPLAY 0.787234 (-3300 3000);
PAINT MONO (-3300 3000);
DISPLAY INVISIBLE (-3300 3000);
FORCEPROP 1 LAST BODY_TYPE PLUMBING
J 0
(-3300 2950);
DISPLAY 1.234043 (-3300 2950);
PAINT GREEN (-3300 2950);
DISPLAY INVISIBLE (-3300 2950);
FORCEPROP 1 LAST HDL_TAP TRUE
J 0
(-2975 2875);
DISPLAY 1.234043 (-2975 2875);
PAINT GREEN (-2975 2875);
DISPLAY INVISIBLE (-2975 2875);
FORCEPROP 1 LAST PATH I163
J 0
(-3300 3000);
DISPLAY 0.936170 (-3300 3000);
PAINT GREEN (-3300 3000);
DISPLAY INVISIBLE (-3300 3000);
FORCEADD TAP..6
(-3300 2900);
FORCEPROP 3 LASTPIN (-3250 2900) SIG_NAME M_J_ODT<1>
J 0
(-3240 2910);
DISPLAY 0.659574 (-3240 2910);
PAINT MONO (-3240 2910);
DISPLAY INVISIBLE (-3240 2910);
FORCEPROP 1 LASTPIN (-3250 2900) BN 1
J 0
(-3300 2910);
DISPLAY 0.617021 (-3300 2910);
PAINT PINK (-3300 2910);
FORCEPROP 2 LAST CDS_LIB mstr_standard
J 0
(-3300 2900);
DISPLAY 0.787234 (-3300 2900);
PAINT MONO (-3300 2900);
DISPLAY INVISIBLE (-3300 2900);
FORCEPROP 1 LAST BODY_TYPE PLUMBING
J 0
(-3300 2850);
DISPLAY 1.234043 (-3300 2850);
PAINT GREEN (-3300 2850);
DISPLAY INVISIBLE (-3300 2850);
FORCEPROP 1 LAST HDL_TAP TRUE
J 0
(-2975 2775);
DISPLAY 1.234043 (-2975 2775);
PAINT GREEN (-2975 2775);
DISPLAY INVISIBLE (-2975 2775);
FORCEPROP 1 LAST PATH I164
J 0
(-3300 2900);
DISPLAY 0.936170 (-3300 2900);
PAINT GREEN (-3300 2900);
DISPLAY INVISIBLE (-3300 2900);
FORCEADD OFFPAGE..1
(-3950 3350);
FORCEPROP 2 LAST $XR0 59 
J 0
(-4171 3350);
DISPLAY 0.638298 (-4171 3350);
PAINT MONO (-4171 3350);
FORCEPROP 2 LAST $XR1 82 
J 0
(-4261 3350);
DISPLAY 0.638298 (-4261 3350);
PAINT MONO (-4261 3350);
FORCEPROP 2 LAST CDS_LIB mstr_standard
J 0
(-3950 3350);
DISPLAY 0.787234 (-3950 3350);
PAINT MONO (-3950 3350);
DISPLAY INVISIBLE (-3950 3350);
FORCEPROP 1 LAST OFFPAGE TRUE
J 0
(-3625 3225);
DISPLAY 0.936170 (-3625 3225);
PAINT GREEN (-3625 3225);
DISPLAY INVISIBLE (-3625 3225);
FORCEPROP 1 LAST COMMENT_BODY TRUE
J 0
(-3825 3250);
DISPLAY 0.936170 (-3825 3250);
PAINT GREEN (-3825 3250);
DISPLAY INVISIBLE (-3825 3250);
FORCEPROP 2 LAST PATH I165
J 0
(-3900 3425);
DISPLAY 0.787234 (-3900 3425);
PAINT MONO (-3900 3425);
DISPLAY INVISIBLE (-3900 3425);
FORCEADD OFFPAGE..1
(-3950 3100);
FORCEPROP 2 LAST $XR0 59 
J 0
(-4171 3100);
DISPLAY 0.638298 (-4171 3100);
PAINT MONO (-4171 3100);
FORCEPROP 2 LAST $XR1 82 
J 0
(-4261 3100);
DISPLAY 0.638298 (-4261 3100);
PAINT MONO (-4261 3100);
FORCEPROP 2 LAST CDS_LIB mstr_standard
J 0
(-3950 3100);
DISPLAY 0.787234 (-3950 3100);
PAINT MONO (-3950 3100);
DISPLAY INVISIBLE (-3950 3100);
FORCEPROP 1 LAST OFFPAGE TRUE
J 0
(-3625 2975);
DISPLAY 0.936170 (-3625 2975);
PAINT GREEN (-3625 2975);
DISPLAY INVISIBLE (-3625 2975);
FORCEPROP 1 LAST COMMENT_BODY TRUE
J 0
(-3825 3000);
DISPLAY 0.936170 (-3825 3000);
PAINT GREEN (-3825 3000);
DISPLAY INVISIBLE (-3825 3000);
FORCEPROP 2 LAST PATH I166
J 0
(-3900 3175);
DISPLAY 0.787234 (-3900 3175);
PAINT MONO (-3900 3175);
DISPLAY INVISIBLE (-3900 3175);
FORCEADD OFFPAGE..1
(-3950 2950);
FORCEPROP 2 LAST $XR0 59 
J 0
(-4171 2950);
DISPLAY 0.638298 (-4171 2950);
PAINT MONO (-4171 2950);
FORCEPROP 2 LAST $XR1 82 
J 0
(-4261 2950);
DISPLAY 0.638298 (-4261 2950);
PAINT MONO (-4261 2950);
FORCEPROP 2 LAST CDS_LIB mstr_standard
J 0
(-3950 2950);
DISPLAY 0.787234 (-3950 2950);
PAINT MONO (-3950 2950);
DISPLAY INVISIBLE (-3950 2950);
FORCEPROP 1 LAST OFFPAGE TRUE
J 0
(-3625 2825);
DISPLAY 0.936170 (-3625 2825);
PAINT GREEN (-3625 2825);
DISPLAY INVISIBLE (-3625 2825);
FORCEPROP 1 LAST COMMENT_BODY TRUE
J 0
(-3825 2850);
DISPLAY 0.936170 (-3825 2850);
PAINT GREEN (-3825 2850);
DISPLAY INVISIBLE (-3825 2850);
FORCEPROP 2 LAST PATH I167
J 0
(-3900 3025);
DISPLAY 0.787234 (-3900 3025);
PAINT MONO (-3900 3025);
DISPLAY INVISIBLE (-3900 3025);
FORCEADD TAP..6
(-3300 2850);
FORCEPROP 3 LASTPIN (-3250 2850) SIG_NAME M_J_ODT<0>
J 0
(-3240 2860);
DISPLAY 0.659574 (-3240 2860);
PAINT MONO (-3240 2860);
DISPLAY INVISIBLE (-3240 2860);
FORCEPROP 1 LASTPIN (-3250 2850) BN 0
J 0
(-3300 2860);
DISPLAY 0.617021 (-3300 2860);
PAINT PINK (-3300 2860);
FORCEPROP 2 LAST CDS_LIB mstr_standard
J 0
(-3300 2850);
DISPLAY 0.787234 (-3300 2850);
PAINT MONO (-3300 2850);
DISPLAY INVISIBLE (-3300 2850);
FORCEPROP 1 LAST BODY_TYPE PLUMBING
J 0
(-3300 2800);
DISPLAY 1.234043 (-3300 2800);
PAINT GREEN (-3300 2800);
DISPLAY INVISIBLE (-3300 2800);
FORCEPROP 1 LAST HDL_TAP TRUE
J 0
(-2975 2725);
DISPLAY 1.234043 (-2975 2725);
PAINT GREEN (-2975 2725);
DISPLAY INVISIBLE (-2975 2725);
FORCEPROP 1 LAST PATH I168
J 0
(-3300 2850);
DISPLAY 0.936170 (-3300 2850);
PAINT GREEN (-3300 2850);
DISPLAY INVISIBLE (-3300 2850);
FORCEADD SCONN288_H44441004..4
(-350 2000);
FORCEPROP 1 LAST LOCATION J1G3
J 0
(-800 3100);
DISPLAY 0.617021 (-800 3100);
PAINT AQUA (-800 3100);
FORCEPROP 1 LAST PART_NUMBER H44441-004
J 0
(-800 950);
DISPLAY 0.617021 (-800 950);
PAINT BLUE (-800 950);
FORCEPROP 1 LAST MATERIAL SCONN
J 0
(-800 3050);
DISPLAY 0.617021 (-800 3050);
PAINT SKYBLUE (-800 3050);
FORCEPROP 2 LASTPIN (-850 2550) $PN 77
J 2
(-860 2560);
DISPLAY 0.617021 (-860 2560);
PAINT ORANGE (-860 2560);
FORCEPROP 2 LASTPIN (-850 2500) $PN 221
J 2
(-860 2510);
DISPLAY 0.617021 (-860 2510);
PAINT ORANGE (-860 2510);
FORCEPROP 2 LASTPIN (-850 2850) $PN 142
J 2
(-860 2860);
DISPLAY 0.617021 (-860 2860);
PAINT ORANGE (-860 2860);
FORCEPROP 2 LASTPIN (-850 2800) $PN 143
J 2
(-860 2810);
DISPLAY 0.617021 (-860 2810);
PAINT ORANGE (-860 2810);
FORCEPROP 2 LASTPIN (-850 2750) $PN 288
J 2
(-860 2760);
DISPLAY 0.617021 (-860 2760);
PAINT ORANGE (-860 2760);
FORCEPROP 2 LASTPIN (-850 2700) $PN 286
J 2
(-860 2710);
DISPLAY 0.617021 (-860 2710);
PAINT ORANGE (-860 2710);
FORCEPROP 2 LASTPIN (-850 2650) $PN 287
J 2
(-860 2660);
DISPLAY 0.617021 (-860 2660);
PAINT ORANGE (-860 2660);
FORCEPROP 2 LASTPIN (-850 2400) $PN 59
J 2
(-860 2410);
DISPLAY 0.617021 (-860 2410);
PAINT ORANGE (-860 2410);
FORCEPROP 2 LASTPIN (-850 2350) $PN 61
J 2
(-860 2360);
DISPLAY 0.617021 (-860 2360);
PAINT ORANGE (-860 2360);
FORCEPROP 2 LASTPIN (-850 2300) $PN 64
J 2
(-860 2310);
DISPLAY 0.617021 (-860 2310);
PAINT ORANGE (-860 2310);
FORCEPROP 2 LASTPIN (-850 2250) $PN 67
J 2
(-860 2260);
DISPLAY 0.617021 (-860 2260);
PAINT ORANGE (-860 2260);
FORCEPROP 2 LASTPIN (-850 2200) $PN 70
J 2
(-860 2210);
DISPLAY 0.617021 (-860 2210);
PAINT ORANGE (-860 2210);
FORCEPROP 2 LASTPIN (-850 2150) $PN 73
J 2
(-860 2160);
DISPLAY 0.617021 (-860 2160);
PAINT ORANGE (-860 2160);
FORCEPROP 2 LASTPIN (-850 2100) $PN 76
J 2
(-860 2110);
DISPLAY 0.617021 (-860 2110);
PAINT ORANGE (-860 2110);
FORCEPROP 2 LASTPIN (-850 2050) $PN 80
J 2
(-860 2060);
DISPLAY 0.617021 (-860 2060);
PAINT ORANGE (-860 2060);
FORCEPROP 2 LASTPIN (-850 2000) $PN 83
J 2
(-860 2010);
DISPLAY 0.617021 (-860 2010);
PAINT ORANGE (-860 2010);
FORCEPROP 2 LASTPIN (-850 1950) $PN 85
J 2
(-860 1960);
DISPLAY 0.617021 (-860 1960);
PAINT ORANGE (-860 1960);
FORCEPROP 2 LASTPIN (-850 1900) $PN 88
J 2
(-860 1910);
DISPLAY 0.617021 (-860 1910);
PAINT ORANGE (-860 1910);
FORCEPROP 2 LASTPIN (-850 1850) $PN 90
J 2
(-860 1860);
DISPLAY 0.617021 (-860 1860);
PAINT ORANGE (-860 1860);
FORCEPROP 2 LASTPIN (-850 1800) $PN 92
J 2
(-860 1810);
DISPLAY 0.617021 (-860 1810);
PAINT ORANGE (-860 1810);
FORCEPROP 2 LASTPIN (-850 1750) $PN 204
J 2
(-860 1760);
DISPLAY 0.617021 (-860 1760);
PAINT ORANGE (-860 1760);
FORCEPROP 2 LASTPIN (-850 1700) $PN 206
J 2
(-860 1710);
DISPLAY 0.617021 (-860 1710);
PAINT ORANGE (-860 1710);
FORCEPROP 2 LASTPIN (-850 1650) $PN 209
J 2
(-860 1660);
DISPLAY 0.617021 (-860 1660);
PAINT ORANGE (-860 1660);
FORCEPROP 2 LASTPIN (-850 1600) $PN 212
J 2
(-860 1610);
DISPLAY 0.617021 (-860 1610);
PAINT ORANGE (-860 1610);
FORCEPROP 2 LASTPIN (-850 1550) $PN 215
J 2
(-860 1560);
DISPLAY 0.617021 (-860 1560);
PAINT ORANGE (-860 1560);
FORCEPROP 2 LASTPIN (-850 1500) $PN 217
J 2
(-860 1510);
DISPLAY 0.617021 (-860 1510);
PAINT ORANGE (-860 1510);
FORCEPROP 2 LASTPIN (-850 1450) $PN 220
J 2
(-860 1460);
DISPLAY 0.617021 (-860 1460);
PAINT ORANGE (-860 1460);
FORCEPROP 2 LASTPIN (-850 1400) $PN 223
J 2
(-860 1410);
DISPLAY 0.617021 (-860 1410);
PAINT ORANGE (-860 1410);
FORCEPROP 2 LASTPIN (-850 1350) $PN 226
J 2
(-860 1360);
DISPLAY 0.617021 (-860 1360);
PAINT ORANGE (-860 1360);
FORCEPROP 2 LASTPIN (-850 1300) $PN 229
J 2
(-860 1310);
DISPLAY 0.617021 (-860 1310);
PAINT ORANGE (-860 1310);
FORCEPROP 2 LASTPIN (-850 1250) $PN 231
J 2
(-860 1260);
DISPLAY 0.617021 (-860 1260);
PAINT ORANGE (-860 1260);
FORCEPROP 2 LASTPIN (-850 1200) $PN 233
J 2
(-860 1210);
DISPLAY 0.617021 (-860 1210);
PAINT ORANGE (-860 1210);
FORCEPROP 2 LASTPIN (-850 1150) $PN 236
J 2
(-860 1160);
DISPLAY 0.617021 (-860 1160);
PAINT ORANGE (-860 1160);
FORCEPROP 2 LASTPIN (150 2850) $PN 1
J 0
(160 2860);
DISPLAY 0.617021 (160 2860);
PAINT ORANGE (160 2860);
FORCEPROP 2 LASTPIN (150 2800) $PN 145
J 0
(160 2810);
DISPLAY 0.617021 (160 2810);
PAINT ORANGE (160 2810);
FORCEPROP 1 LAST PACK_TYPE PIP
J 0
(-800 3150);
PAINT SKYBLUE (-800 3150);
DISPLAY INVISIBLE (-800 3150);
FORCEPROP 2 LAST BOM_COST MEM
J 0
(-350 2000);
PAINT ORANGE (-350 2000);
DISPLAY INVISIBLE (-350 2000);
FORCEPROP 2 LAST CDS_LIB mstr_sconn
J 0
(-350 2000);
PAINT ORANGE (-350 2000);
DISPLAY INVISIBLE (-350 2000);
FORCEPROP 2 LAST SEC_TYPE PIP
J 0
(-800 3150);
DISPLAY 1.021277 (-800 3150);
PAINT ORANGE (-800 3150);
DISPLAY INVISIBLE (-800 3150);
FORCEPROP 2 LAST SEC 4
J 0
(-800 3150);
DISPLAY 0.680851 (-800 3150);
PAINT MONO (-800 3150);
DISPLAY INVISIBLE (-800 3150);
FORCEPROP 2 LAST CDS_LOCATION J1G3
J 0
(-800 3100);
DISPLAY 0.617021 (-800 3100);
PAINT AQUA (-800 3100);
DISPLAY INVISIBLE (-800 3100);
FORCEPROP 1 LAST PATH I169
J 0
(-350 3050);
PAINT GREEN (-350 3050);
DISPLAY INVISIBLE (-350 3050);
FORCEPROP 2 LAST ROOM DDR4_CH_J
J 0
(-350 2000);
PAINT ORANGE (-350 2000);
DISPLAY INVISIBLE (-350 2000);
FORCEADD PVDDQ_GHJ..1
(-1475 2525);
FORCEPROP 3 LASTPIN (-1475 2475) SIG_NAME PVDDQ_GHJ\g
J 0
(-1465 2485);
DISPLAY 0.659574 (-1465 2485);
PAINT MONO (-1465 2485);
DISPLAY INVISIBLE (-1465 2485);
FORCEPROP 1 LAST VOLTAGE 1.2V
J 0
(-1520 2482);
DISPLAY 0.340426 (-1520 2482);
PAINT SKYBLUE (-1520 2482);
DISPLAY INVISIBLE (-1520 2482);
FORCEPROP 2 LAST BOM_COST MEM
J 0
(-1475 2530);
PAINT ORANGE (-1475 2530);
DISPLAY INVISIBLE (-1475 2530);
FORCEPROP 2 LAST CDS_LIB mstr_symbols
J 0
(-1475 2525);
PAINT ORANGE (-1475 2525);
DISPLAY INVISIBLE (-1475 2525);
FORCEPROP 1 LAST BODY_TYPE PLUMBING
J 0
(-1520 2482);
DISPLAY 0.340426 (-1520 2482);
PAINT GREEN (-1520 2482);
DISPLAY INVISIBLE (-1520 2482);
FORCEPROP 1 LAST PATH I17
J 0
(-1425 2550);
DISPLAY 0.872340 (-1425 2550);
PAINT AQUA (-1425 2550);
DISPLAY INVISIBLE (-1425 2550);
FORCEPROP 2 LAST ROOM DDR4_CH_J
J 0
(-1475 2625);
DISPLAY 0.787234 (-1475 2625);
PAINT ORANGE (-1475 2625);
DISPLAY INVISIBLE (-1475 2625);
FORCEPROP 1 LAST HDL_POWER PVDDQ_GHJ
J 1
(-1475 2575);
DISPLAY 0.872340 (-1475 2575);
PAINT GREEN (-1475 2575);
DISPLAY INVISIBLE (-1475 2575);
FORCEADD GND..1
R 2
(2450 1100);
FORCEPROP 3 LASTPIN (2450 1150) SIG_NAME GND\g
J 0
(2460 1160);
DISPLAY 0.659574 (2460 1160);
PAINT MONO (2460 1160);
DISPLAY INVISIBLE (2460 1160);
FORCEPROP 1 LAST VOLTAGE 0
J 0
(2450 1100);
PAINT SKYBLUE (2450 1100);
DISPLAY INVISIBLE (2450 1100);
FORCEPROP 2 LAST BOM_COST MEM
J 0
(2450 1105);
PAINT ORANGE (2450 1105);
DISPLAY INVISIBLE (2450 1105);
FORCEPROP 2 LAST CDS_LIB mstr_symbols
J 0
(2450 1100);
DISPLAY 0.787234 (2450 1100);
PAINT MONO (2450 1100);
DISPLAY INVISIBLE (2450 1100);
FORCEPROP 1 LAST SIZE 1B
J 2
(2375 1050);
DISPLAY 1.170213 (2375 1050);
PAINT GREEN (2375 1050);
DISPLAY INVISIBLE (2375 1050);
FORCEPROP 1 LAST BODY_TYPE PLUMBING
J 2
(2495 1057);
DISPLAY 0.340426 (2495 1057);
PAINT GREEN (2495 1057);
DISPLAY INVISIBLE (2495 1057);
FORCEPROP 1 LAST PATH I170
J 2
(2375 1100);
DISPLAY 1.404255 (2375 1100);
PAINT GREEN (2375 1100);
DISPLAY INVISIBLE (2375 1100);
FORCEPROP 2 LAST ROOM DDR4_CH_J
J 0
(2450 1105);
PAINT ORANGE (2450 1105);
DISPLAY INVISIBLE (2450 1105);
FORCEPROP 1 LAST HDL_POWER GND
J 2
(2450 1250);
DISPLAY 0.553191 (2450 1250);
PAINT GREEN (2450 1250);
DISPLAY INVISIBLE (2450 1250);
FORCEADD OFFPAGE..1
(-3950 1750);
FORCEPROP 2 LAST $XR0 99 
J 0
(-4201 1750);
DISPLAY 0.638298 (-4201 1750);
PAINT MONO (-4201 1750);
FORCEPROP 2 LAST $XR1 77 
J 0
(-4291 1750);
DISPLAY 0.638298 (-4291 1750);
PAINT MONO (-4291 1750);
FORCEPROP 2 LAST $XR2 78 
J 0
(-4381 1750);
DISPLAY 0.638298 (-4381 1750);
PAINT MONO (-4381 1750);
FORCEPROP 2 LAST $XR3 79 
J 0
(-4471 1750);
DISPLAY 0.638298 (-4471 1750);
PAINT MONO (-4471 1750);
FORCEPROP 2 LAST $XR4 80 
J 0
(-4561 1750);
DISPLAY 0.638298 (-4561 1750);
PAINT MONO (-4561 1750);
FORCEPROP 2 LAST $XR5 82 
J 0
(-4651 1750);
DISPLAY 0.638298 (-4651 1750);
PAINT MONO (-4651 1750);
FORCEPROP 2 LAST CDS_LIB mstr_standard
J 0
(-3950 1750);
DISPLAY 0.787234 (-3950 1750);
PAINT MONO (-3950 1750);
DISPLAY INVISIBLE (-3950 1750);
FORCEPROP 1 LAST OFFPAGE TRUE
J 0
(-3625 1625);
DISPLAY 0.936170 (-3625 1625);
PAINT GREEN (-3625 1625);
DISPLAY INVISIBLE (-3625 1625);
FORCEPROP 1 LAST COMMENT_BODY TRUE
J 0
(-3825 1650);
DISPLAY 0.936170 (-3825 1650);
PAINT GREEN (-3825 1650);
DISPLAY INVISIBLE (-3825 1650);
FORCEPROP 2 LAST PATH I171
J 0
(-4225 1800);
DISPLAY 0.787234 (-4225 1800);
PAINT ORANGE (-4225 1800);
DISPLAY INVISIBLE (-4225 1800);
FORCEADD OFFPAGE..6
(-3950 1800);
FORCEPROP 2 LAST $XR0 77 
J 0
(-4229 1800);
DISPLAY 0.638298 (-4229 1800);
PAINT MONO (-4229 1800);
FORCEPROP 2 LAST $XR1 78 
J 0
(-4319 1800);
DISPLAY 0.638298 (-4319 1800);
PAINT MONO (-4319 1800);
FORCEPROP 2 LAST $XR2 79 
J 0
(-4409 1800);
DISPLAY 0.638298 (-4409 1800);
PAINT MONO (-4409 1800);
FORCEPROP 2 LAST $XR3 80 
J 0
(-4499 1800);
DISPLAY 0.638298 (-4499 1800);
PAINT MONO (-4499 1800);
FORCEPROP 2 LAST $XR4 82 
J 0
(-4589 1800);
DISPLAY 0.638298 (-4589 1800);
PAINT MONO (-4589 1800);
FORCEPROP 2 LAST $XR5 99 
J 0
(-4679 1800);
DISPLAY 0.638298 (-4679 1800);
PAINT MONO (-4679 1800);
FORCEPROP 2 LASTPIN (-3900 1800) SIG_NAME SMB_DDR_GHJ_VPP_SDA
J 0
(-3860 1810);
DISPLAY 0.617021 (-3860 1810);
PAINT ORANGE (-3860 1810);
FORCEPROP 2 LAST CDS_LIB mstr_standard
J 0
(-3950 1800);
DISPLAY 0.787234 (-3950 1800);
PAINT MONO (-3950 1800);
DISPLAY INVISIBLE (-3950 1800);
FORCEPROP 1 LAST OFFPAGE TRUE
J 0
(-3625 1675);
DISPLAY 0.936170 (-3625 1675);
PAINT GREEN (-3625 1675);
DISPLAY INVISIBLE (-3625 1675);
FORCEPROP 1 LAST COMMENT_BODY TRUE
J 0
(-3850 1725);
DISPLAY 0.936170 (-3850 1725);
PAINT GREEN (-3850 1725);
DISPLAY INVISIBLE (-3850 1725);
FORCEPROP 2 LAST PATH I172
J 0
(-4275 1850);
DISPLAY 0.787234 (-4275 1850);
PAINT ORANGE (-4275 1850);
DISPLAY INVISIBLE (-4275 1850);
FORCEADD OFFPAGE..1
(-4700 1650);
FORCEPROP 2 LAST $XR0 100 
J 0
(-4952 1650);
DISPLAY 0.638298 (-4952 1650);
PAINT MONO (-4952 1650);
FORCEPROP 2 LAST $XR1 82 
J 0
(-5042 1650);
DISPLAY 0.638298 (-5042 1650);
PAINT MONO (-5042 1650);
FORCEPROP 2 LAST CDS_LIB mstr_standard
J 0
(-4700 1650);
DISPLAY 0.787234 (-4700 1650);
PAINT MONO (-4700 1650);
DISPLAY INVISIBLE (-4700 1650);
FORCEPROP 1 LAST OFFPAGE TRUE
J 0
(-4375 1525);
DISPLAY 0.936170 (-4375 1525);
PAINT GREEN (-4375 1525);
DISPLAY INVISIBLE (-4375 1525);
FORCEPROP 1 LAST COMMENT_BODY TRUE
J 0
(-4575 1550);
DISPLAY 0.936170 (-4575 1550);
PAINT GREEN (-4575 1550);
DISPLAY INVISIBLE (-4575 1550);
FORCEPROP 2 LAST PATH I173
J 0
(-4950 1700);
DISPLAY 0.787234 (-4950 1700);
PAINT ORANGE (-4950 1700);
DISPLAY INVISIBLE (-4950 1700);
FORCEADD GND..1
R 2
(-5200 1750);
FORCEPROP 3 LASTPIN (-5200 1800) SIG_NAME GND\g
J 0
(-5190 1810);
DISPLAY 0.659574 (-5190 1810);
PAINT MONO (-5190 1810);
DISPLAY INVISIBLE (-5190 1810);
FORCEPROP 1 LAST VOLTAGE 0
J 0
(-5200 1750);
PAINT SKYBLUE (-5200 1750);
DISPLAY INVISIBLE (-5200 1750);
FORCEPROP 2 LAST BOM_COST MEM
J 0
(-5200 1755);
PAINT ORANGE (-5200 1755);
DISPLAY INVISIBLE (-5200 1755);
FORCEPROP 2 LAST CDS_LIB mstr_symbols
J 0
(-5200 1750);
DISPLAY 0.787234 (-5200 1750);
PAINT MONO (-5200 1750);
DISPLAY INVISIBLE (-5200 1750);
FORCEPROP 1 LAST SIZE 1B
J 2
(-5275 1700);
DISPLAY 1.170213 (-5275 1700);
PAINT GREEN (-5275 1700);
DISPLAY INVISIBLE (-5275 1700);
FORCEPROP 1 LAST BODY_TYPE PLUMBING
J 2
(-5155 1707);
DISPLAY 0.340426 (-5155 1707);
PAINT GREEN (-5155 1707);
DISPLAY INVISIBLE (-5155 1707);
FORCEPROP 1 LAST PATH I175
J 2
(-5275 1750);
DISPLAY 1.404255 (-5275 1750);
PAINT GREEN (-5275 1750);
DISPLAY INVISIBLE (-5275 1750);
FORCEPROP 2 LAST ROOM DDR4_CH_J
J 0
(-5200 1755);
PAINT ORANGE (-5200 1755);
DISPLAY INVISIBLE (-5200 1755);
FORCEPROP 1 LAST HDL_POWER GND
J 2
(-5200 1900);
DISPLAY 0.553191 (-5200 1900);
PAINT GREEN (-5200 1900);
DISPLAY INVISIBLE (-5200 1900);
FORCEADD OFFPAGE..5
(-4325 2450);
FORCEPROP 2 LAST $XR0 43 
J 0
(-4579 2450);
DISPLAY 0.638298 (-4579 2450);
PAINT MONO (-4579 2450);
FORCEPROP 2 LAST $XR1 44 
J 0
(-4669 2450);
DISPLAY 0.638298 (-4669 2450);
PAINT MONO (-4669 2450);
FORCEPROP 2 LAST $XR2 45 
J 0
(-4759 2450);
DISPLAY 0.638298 (-4759 2450);
PAINT MONO (-4759 2450);
FORCEPROP 2 LAST $XR3 46 
J 0
(-4849 2450);
DISPLAY 0.638298 (-4849 2450);
PAINT MONO (-4849 2450);
FORCEPROP 2 LAST $XR4 47 
J 0
(-4939 2450);
DISPLAY 0.638298 (-4939 2450);
PAINT MONO (-4939 2450);
FORCEPROP 2 LAST $XR5 48 
J 0
(-5029 2450);
DISPLAY 0.638298 (-5029 2450);
PAINT MONO (-5029 2450);
FORCEPROP 2 LAST $XR6 49 
J 0
(-5119 2450);
DISPLAY 0.638298 (-5119 2450);
PAINT MONO (-5119 2450);
FORCEPROP 2 LAST $XR7 50 
J 0
(-5209 2450);
DISPLAY 0.638298 (-5209 2450);
PAINT MONO (-5209 2450);
FORCEPROP 2 LAST $XR8 51 
J 0
(-5299 2450);
DISPLAY 0.638298 (-5299 2450);
PAINT MONO (-5299 2450);
FORCEPROP 2 LAST $XR9 52 
J 0
(-4579 2414);
DISPLAY 0.638298 (-4579 2414);
PAINT MONO (-4579 2414);
FORCEPROP 2 LAST $XR10 53 
J 0
(-4669 2414);
DISPLAY 0.638298 (-4669 2414);
PAINT MONO (-4669 2414);
FORCEPROP 2 LAST $XR11 54 
J 0
(-4759 2414);
DISPLAY 0.638298 (-4759 2414);
PAINT MONO (-4759 2414);
FORCEPROP 2 LAST $XR12 77 
J 0
(-4849 2414);
DISPLAY 0.638298 (-4849 2414);
PAINT MONO (-4849 2414);
FORCEPROP 2 LAST $XR13 78 
J 0
(-4939 2414);
DISPLAY 0.638298 (-4939 2414);
PAINT MONO (-4939 2414);
FORCEPROP 2 LAST $XR14 79 
J 0
(-5029 2414);
DISPLAY 0.638298 (-5029 2414);
PAINT MONO (-5029 2414);
FORCEPROP 2 LAST $XR15 80 
J 0
(-5119 2414);
DISPLAY 0.638298 (-5119 2414);
PAINT MONO (-5119 2414);
FORCEPROP 2 LAST $XR16 82 
J 0
(-5209 2414);
DISPLAY 0.638298 (-5209 2414);
PAINT MONO (-5209 2414);
FORCEPROP 2 LAST $XR17 83 
J 0
(-5299 2414);
DISPLAY 0.638298 (-5299 2414);
PAINT MONO (-5299 2414);
FORCEPROP 2 LAST $XR18 84 
J 0
(-4579 2486);
DISPLAY 0.638298 (-4579 2486);
PAINT MONO (-4579 2486);
FORCEPROP 2 LAST $XR19 85 
J 0
(-4669 2486);
DISPLAY 0.638298 (-4669 2486);
PAINT MONO (-4669 2486);
FORCEPROP 2 LAST $XR20 86 
J 0
(-4759 2486);
DISPLAY 0.638298 (-4759 2486);
PAINT MONO (-4759 2486);
FORCEPROP 2 LAST $XR21 87 
J 0
(-4849 2486);
DISPLAY 0.638298 (-4849 2486);
PAINT MONO (-4849 2486);
FORCEPROP 2 LAST $XR22 88 
J 0
(-4939 2486);
DISPLAY 0.638298 (-4939 2486);
PAINT MONO (-4939 2486);
FORCEPROP 2 LAST $XR23 94 
J 0
(-5029 2486);
DISPLAY 0.638298 (-5029 2486);
PAINT MONO (-5029 2486);
FORCEPROP 2 LAST CDS_LIB mstr_standard
J 0
(-4325 2450);
DISPLAY 0.787234 (-4325 2450);
PAINT MONO (-4325 2450);
DISPLAY INVISIBLE (-4325 2450);
FORCEPROP 1 LAST OFFPAGE TRUE
J 0
(-4000 2325);
DISPLAY 1.404255 (-4000 2325);
PAINT GREEN (-4000 2325);
DISPLAY INVISIBLE (-4000 2325);
FORCEPROP 1 LAST COMMENT_BODY TRUE
J 0
(-4225 2375);
DISPLAY 1.404255 (-4225 2375);
PAINT GREEN (-4225 2375);
DISPLAY INVISIBLE (-4225 2375);
FORCEPROP 2 LAST PATH I176
J 0
(-4275 2525);
DISPLAY 0.787234 (-4275 2525);
PAINT ORANGE (-4275 2525);
DISPLAY INVISIBLE (-4275 2525);
FORCEADD GND..1
(-4550 1200);
FORCEPROP 3 LASTPIN (-4550 1250) SIG_NAME GND\g
J 0
(-4540 1260);
DISPLAY 0.659574 (-4540 1260);
PAINT MONO (-4540 1260);
DISPLAY INVISIBLE (-4540 1260);
FORCEPROP 1 LAST VOLTAGE 0
J 0
(-4550 1200);
PAINT SKYBLUE (-4550 1200);
DISPLAY INVISIBLE (-4550 1200);
FORCEPROP 2 LAST CDS_LIB mstr_symbols
J 0
(-4550 1200);
PAINT ORANGE (-4550 1200);
DISPLAY INVISIBLE (-4550 1200);
FORCEPROP 1 LAST SIZE 1B
J 0
(-4475 1150);
DISPLAY 1.787234 (-4475 1150);
PAINT GREEN (-4475 1150);
DISPLAY INVISIBLE (-4475 1150);
FORCEPROP 2 LAST BOM_COST MEM
J 0
(-4550 1205);
PAINT ORANGE (-4550 1205);
DISPLAY INVISIBLE (-4550 1205);
FORCEPROP 1 LAST BODY_TYPE PLUMBING
J 0
(-4595 1157);
DISPLAY 0.340426 (-4595 1157);
PAINT GREEN (-4595 1157);
DISPLAY INVISIBLE (-4595 1157);
FORCEPROP 1 LAST PATH I177
J 0
(-4475 1200);
DISPLAY 1.404255 (-4475 1200);
PAINT GREEN (-4475 1200);
DISPLAY INVISIBLE (-4475 1200);
FORCEPROP 2 LAST ROOM DDR4_CH_J
J 0
(-4550 1205);
PAINT ORANGE (-4550 1205);
DISPLAY INVISIBLE (-4550 1205);
FORCEPROP 1 LAST HDL_POWER GND
J 0
(-4550 1350);
DISPLAY 1.404255 (-4550 1350);
PAINT GREEN (-4550 1350);
DISPLAY INVISIBLE (-4550 1350);
FORCEADD CAP_A..1
R 2
(-4550 1450);
FORCEPROP 1 LAST LOCATION C9U10
J 2
(-4600 1550);
DISPLAY 0.617021 (-4600 1550);
PAINT AQUA (-4600 1550);
FORCEPROP 1 LAST PART_NUMBER A36096-045
J 2
(-4600 1300);
DISPLAY 0.617021 (-4600 1300);
PAINT BLUE (-4600 1300);
FORCEPROP 1 LAST VALUE 0.01UF
J 2
(-4600 1500);
DISPLAY 0.617021 (-4600 1500);
PAINT SKYBLUE (-4600 1500);
FORCEPROP 1 LAST TOLERANCE 10%
J 2
(-4600 1400);
DISPLAY 0.617021 (-4600 1400);
PAINT SKYBLUE (-4600 1400);
FORCEPROP 1 LAST PACK_TYPE 0402V
J 2
(-4600 1250);
DISPLAY 0.617021 (-4600 1250);
PAINT SKYBLUE (-4600 1250);
FORCEPROP 1 LAST VOLTAGE 25V
J 2
(-4600 1450);
DISPLAY 0.617021 (-4600 1450);
PAINT SKYBLUE (-4600 1450);
FORCEPROP 1 LAST MATERIAL X7R
J 2
(-4600 1350);
DISPLAY 0.617021 (-4600 1350);
PAINT SKYBLUE (-4600 1350);
FORCEPROP 2 LAST CDS_LOCATION C9U10
J 2
(-4600 1550);
DISPLAY 0.617021 (-4600 1550);
PAINT AQUA (-4600 1550);
DISPLAY INVISIBLE (-4600 1550);
FORCEPROP 2 LAST BOM_COST MEM
J 0
(-4550 1450);
PAINT ORANGE (-4550 1450);
DISPLAY INVISIBLE (-4550 1450);
FORCEPROP 2 LAST CDS_LIB dev_discrete
J 0
(-4550 1450);
PAINT ORANGE (-4550 1450);
DISPLAY INVISIBLE (-4550 1450);
FORCEPROP 2 LAST CDS_SEC 1
J 2
(-4600 1650);
PAINT MONO (-4600 1650);
DISPLAY INVISIBLE (-4600 1650);
FORCEPROP 2 LAST $SEC 1
J 0
(-4600 1650);
PAINT MONO (-4600 1650);
DISPLAY INVISIBLE (-4600 1650);
FORCEPROP 1 LAST PATH I178
J 2
(-4600 1600);
DISPLAY 0.978723 (-4600 1600);
PAINT WHITE (-4600 1600);
DISPLAY INVISIBLE (-4600 1600);
FORCEPROP 2 LAST ROOM DDR4_CH_J
J 0
(-4550 1450);
PAINT ORANGE (-4550 1450);
DISPLAY INVISIBLE (-4550 1450);
FORCEPROP 1 LASTPIN (-4550 1550) $PN 1
J 2
(-4560 1530);
DISPLAY 0.787234 (-4560 1530);
PAINT ORANGE (-4560 1530);
DISPLAY INVISIBLE (-4560 1530);
FORCEPROP 1 LASTPIN (-4550 1350) $PN 2
J 2
(-4560 1330);
DISPLAY 0.787234 (-4560 1330);
PAINT ORANGE (-4560 1330);
DISPLAY INVISIBLE (-4560 1330);
FORCEADD PVPP_GHJ..1
(-1050 3000);
FORCEPROP 3 LASTPIN (-1050 2950) SIG_NAME PVPP_GHJ\g
J 0
(-1040 2960);
DISPLAY 0.659574 (-1040 2960);
PAINT MONO (-1040 2960);
DISPLAY INVISIBLE (-1040 2960);
FORCEPROP 1 LAST VOLTAGE 2.5V
J 0
(-1095 2957);
DISPLAY 0.340426 (-1095 2957);
PAINT SKYBLUE (-1095 2957);
DISPLAY INVISIBLE (-1095 2957);
FORCEPROP 0 LAST BOM_COST MEM
J 0
(-1050 3100);
PAINT ORANGE (-1050 3100);
DISPLAY INVISIBLE (-1050 3100);
FORCEPROP 2 LAST CDS_LIB mstr_symbols
J 0
(-1050 3000);
PAINT ORANGE (-1050 3000);
DISPLAY INVISIBLE (-1050 3000);
FORCEPROP 1 LAST BODY_TYPE PLUMBING
J 0
(-1095 2957);
DISPLAY 0.340426 (-1095 2957);
PAINT GREEN (-1095 2957);
DISPLAY INVISIBLE (-1095 2957);
FORCEPROP 1 LAST PATH I179
J 0
(-1000 3025);
DISPLAY 0.872340 (-1000 3025);
PAINT AQUA (-1000 3025);
DISPLAY INVISIBLE (-1000 3025);
FORCEPROP 2 LAST ROOM DDR4_CH_J
J 0
(-1050 3100);
PAINT ORANGE (-1050 3100);
DISPLAY INVISIBLE (-1050 3100);
FORCEPROP 1 LAST HDL_POWER PVPP_GHJ
J 1
(-1050 3050);
DISPLAY 0.872340 (-1050 3050);
PAINT GREEN (-1050 3050);
DISPLAY INVISIBLE (-1050 3050);
FORCEADD PVTT_GHJ..1
(-1200 2700);
FORCEPROP 3 LASTPIN (-1200 2650) SIG_NAME PVTT_GHJ\g
J 0
(-1190 2660);
DISPLAY 0.659574 (-1190 2660);
PAINT MONO (-1190 2660);
DISPLAY INVISIBLE (-1190 2660);
FORCEPROP 1 LAST VOLTAGE 0.6V
J 0
(-1245 2657);
DISPLAY 0.340426 (-1245 2657);
PAINT SKYBLUE (-1245 2657);
DISPLAY INVISIBLE (-1245 2657);
FORCEPROP 2 LAST BOM_COST MEM
J 0
(-1200 2705);
PAINT ORANGE (-1200 2705);
DISPLAY INVISIBLE (-1200 2705);
FORCEPROP 2 LAST CDS_LIB mstr_symbols
J 0
(-1200 2700);
PAINT ORANGE (-1200 2700);
DISPLAY INVISIBLE (-1200 2700);
FORCEPROP 1 LAST BODY_TYPE PLUMBING
J 0
(-1245 2657);
DISPLAY 0.340426 (-1245 2657);
PAINT GREEN (-1245 2657);
DISPLAY INVISIBLE (-1245 2657);
FORCEPROP 1 LAST PATH I18
J 0
(-1150 2725);
DISPLAY 0.872340 (-1150 2725);
PAINT AQUA (-1150 2725);
DISPLAY INVISIBLE (-1150 2725);
FORCEPROP 2 LAST ROOM DDR4_CH_J
J 0
(-1200 2800);
DISPLAY 0.787234 (-1200 2800);
PAINT ORANGE (-1200 2800);
DISPLAY INVISIBLE (-1200 2800);
FORCEPROP 1 LAST HDL_POWER PVTT_GHJ
J 1
(-1200 2750);
DISPLAY 0.872340 (-1200 2750);
PAINT GREEN (-1200 2750);
DISPLAY INVISIBLE (-1200 2750);
FORCEADD PVPP_GHJ..1
(-5200 2150);
FORCEPROP 3 LASTPIN (-5200 2100) SIG_NAME PVPP_GHJ\g
J 0
(-5190 2110);
DISPLAY 0.659574 (-5190 2110);
PAINT MONO (-5190 2110);
DISPLAY INVISIBLE (-5190 2110);
FORCEPROP 1 LAST VOLTAGE 2.5V
J 0
(-5245 2107);
DISPLAY 0.340426 (-5245 2107);
PAINT SKYBLUE (-5245 2107);
DISPLAY INVISIBLE (-5245 2107);
FORCEPROP 0 LAST BOM_COST MEM
J 0
(-5200 2250);
PAINT ORANGE (-5200 2250);
DISPLAY INVISIBLE (-5200 2250);
FORCEPROP 2 LAST CDS_LIB mstr_symbols
J 0
(-5200 2150);
PAINT ORANGE (-5200 2150);
DISPLAY INVISIBLE (-5200 2150);
FORCEPROP 1 LAST BODY_TYPE PLUMBING
J 0
(-5245 2107);
DISPLAY 0.340426 (-5245 2107);
PAINT GREEN (-5245 2107);
DISPLAY INVISIBLE (-5245 2107);
FORCEPROP 1 LAST PATH I180
J 0
(-5150 2175);
DISPLAY 0.872340 (-5150 2175);
PAINT AQUA (-5150 2175);
DISPLAY INVISIBLE (-5150 2175);
FORCEPROP 2 LAST ROOM DDR4_CH_J
J 0
(-5200 2250);
PAINT ORANGE (-5200 2250);
DISPLAY INVISIBLE (-5200 2250);
FORCEPROP 1 LAST HDL_POWER PVPP_GHJ
J 1
(-5200 2200);
DISPLAY 0.872340 (-5200 2200);
PAINT GREEN (-5200 2200);
DISPLAY INVISIBLE (-5200 2200);
FORCEADD OFFPAGE..1
(-3950 1350);
FORCEPROP 2 LAST $XR0 89 
J 0
(-4171 1350);
DISPLAY 0.638298 (-4171 1350);
PAINT MONO (-4171 1350);
FORCEPROP 2 LAST $XR1 77 
J 0
(-4261 1350);
DISPLAY 0.638298 (-4261 1350);
PAINT MONO (-4261 1350);
FORCEPROP 2 LAST $XR2 78 
J 0
(-4351 1350);
DISPLAY 0.638298 (-4351 1350);
PAINT MONO (-4351 1350);
FORCEPROP 2 LAST $XR3 79 
J 0
(-4441 1350);
DISPLAY 0.638298 (-4441 1350);
PAINT MONO (-4441 1350);
FORCEPROP 2 LAST $XR4 80 
J 0
(-4531 1350);
DISPLAY 0.638298 (-4531 1350);
PAINT MONO (-4531 1350);
FORCEPROP 2 LAST $XR5 82 
J 0
(-4171 1314);
DISPLAY 0.638298 (-4171 1314);
PAINT MONO (-4171 1314);
FORCEPROP 2 LAST CDS_LIB mstr_standard
J 0
(-3950 1350);
PAINT ORANGE (-3950 1350);
DISPLAY INVISIBLE (-3950 1350);
FORCEPROP 1 LAST OFFPAGE TRUE
J 0
(-3625 1225);
DISPLAY 0.936170 (-3625 1225);
PAINT GREEN (-3625 1225);
DISPLAY INVISIBLE (-3625 1225);
FORCEPROP 1 LAST COMMENT_BODY TRUE
J 0
(-3825 1250);
DISPLAY 0.936170 (-3825 1250);
PAINT GREEN (-3825 1250);
DISPLAY INVISIBLE (-3825 1250);
FORCEPROP 2 LAST PATH I181
J 0
(-3900 1425);
PAINT ORANGE (-3900 1425);
DISPLAY INVISIBLE (-3900 1425);
FORCEADD SCONN288_H44441004..3
(1750 2400);
FORCEPROP 1 LAST LOCATION J1G3
J 0
(1300 3800);
DISPLAY 0.617021 (1300 3800);
PAINT AQUA (1300 3800);
FORCEPROP 1 LAST PART_NUMBER H44441-004
J 0
(1300 1050);
DISPLAY 0.617021 (1300 1050);
PAINT BLUE (1300 1050);
FORCEPROP 1 LAST MATERIAL SCONN
J 0
(1300 3750);
DISPLAY 0.617021 (1300 3750);
PAINT SKYBLUE (1300 3750);
FORCEPROP 2 LASTPIN (1250 3550) $PN 2
J 2
(1240 3560);
DISPLAY 0.617021 (1240 3560);
PAINT ORANGE (1240 3560);
FORCEPROP 2 LASTPIN (1250 3500) $PN 4
J 2
(1240 3510);
DISPLAY 0.617021 (1240 3510);
PAINT ORANGE (1240 3510);
FORCEPROP 2 LASTPIN (1250 3450) $PN 6
J 2
(1240 3460);
DISPLAY 0.617021 (1240 3460);
PAINT ORANGE (1240 3460);
FORCEPROP 2 LASTPIN (1250 3400) $PN 9
J 2
(1240 3410);
DISPLAY 0.617021 (1240 3410);
PAINT ORANGE (1240 3410);
FORCEPROP 2 LASTPIN (1250 3350) $PN 11
J 2
(1240 3360);
DISPLAY 0.617021 (1240 3360);
PAINT ORANGE (1240 3360);
FORCEPROP 2 LASTPIN (1250 3300) $PN 13
J 2
(1240 3310);
DISPLAY 0.617021 (1240 3310);
PAINT ORANGE (1240 3310);
FORCEPROP 2 LASTPIN (1250 3250) $PN 15
J 2
(1240 3260);
DISPLAY 0.617021 (1240 3260);
PAINT ORANGE (1240 3260);
FORCEPROP 2 LASTPIN (1250 3200) $PN 17
J 2
(1240 3210);
DISPLAY 0.617021 (1240 3210);
PAINT ORANGE (1240 3210);
FORCEPROP 2 LASTPIN (1250 3150) $PN 20
J 2
(1240 3160);
DISPLAY 0.617021 (1240 3160);
PAINT ORANGE (1240 3160);
FORCEPROP 2 LASTPIN (1250 3100) $PN 22
J 2
(1240 3110);
DISPLAY 0.617021 (1240 3110);
PAINT ORANGE (1240 3110);
FORCEPROP 2 LASTPIN (1250 3050) $PN 24
J 2
(1240 3060);
DISPLAY 0.617021 (1240 3060);
PAINT ORANGE (1240 3060);
FORCEPROP 2 LASTPIN (1250 3000) $PN 26
J 2
(1240 3010);
DISPLAY 0.617021 (1240 3010);
PAINT ORANGE (1240 3010);
FORCEPROP 2 LASTPIN (1250 2950) $PN 28
J 2
(1240 2960);
DISPLAY 0.617021 (1240 2960);
PAINT ORANGE (1240 2960);
FORCEPROP 2 LASTPIN (1250 2900) $PN 31
J 2
(1240 2910);
DISPLAY 0.617021 (1240 2910);
PAINT ORANGE (1240 2910);
FORCEPROP 2 LASTPIN (1250 2850) $PN 33
J 2
(1240 2860);
DISPLAY 0.617021 (1240 2860);
PAINT ORANGE (1240 2860);
FORCEPROP 2 LASTPIN (1250 2800) $PN 35
J 2
(1240 2810);
DISPLAY 0.617021 (1240 2810);
PAINT ORANGE (1240 2810);
FORCEPROP 2 LASTPIN (1250 2750) $PN 37
J 2
(1240 2760);
DISPLAY 0.617021 (1240 2760);
PAINT ORANGE (1240 2760);
FORCEPROP 2 LASTPIN (1250 2700) $PN 39
J 2
(1240 2710);
DISPLAY 0.617021 (1240 2710);
PAINT ORANGE (1240 2710);
FORCEPROP 2 LASTPIN (1250 2650) $PN 42
J 2
(1240 2660);
DISPLAY 0.617021 (1240 2660);
PAINT ORANGE (1240 2660);
FORCEPROP 2 LASTPIN (1250 2600) $PN 44
J 2
(1240 2610);
DISPLAY 0.617021 (1240 2610);
PAINT ORANGE (1240 2610);
FORCEPROP 2 LASTPIN (1250 2550) $PN 46
J 2
(1240 2560);
DISPLAY 0.617021 (1240 2560);
PAINT ORANGE (1240 2560);
FORCEPROP 2 LASTPIN (1250 2500) $PN 48
J 2
(1240 2510);
DISPLAY 0.617021 (1240 2510);
PAINT ORANGE (1240 2510);
FORCEPROP 2 LASTPIN (1250 2450) $PN 50
J 2
(1240 2460);
DISPLAY 0.617021 (1240 2460);
PAINT ORANGE (1240 2460);
FORCEPROP 2 LASTPIN (1250 2400) $PN 53
J 2
(1240 2410);
DISPLAY 0.617021 (1240 2410);
PAINT ORANGE (1240 2410);
FORCEPROP 2 LASTPIN (1250 2350) $PN 55
J 2
(1240 2360);
DISPLAY 0.617021 (1240 2360);
PAINT ORANGE (1240 2360);
FORCEPROP 2 LASTPIN (1250 2300) $PN 57
J 2
(1240 2310);
DISPLAY 0.617021 (1240 2310);
PAINT ORANGE (1240 2310);
FORCEPROP 2 LASTPIN (1250 2250) $PN 94
J 2
(1240 2260);
DISPLAY 0.617021 (1240 2260);
PAINT ORANGE (1240 2260);
FORCEPROP 2 LASTPIN (1250 2200) $PN 96
J 2
(1240 2210);
DISPLAY 0.617021 (1240 2210);
PAINT ORANGE (1240 2210);
FORCEPROP 2 LASTPIN (1250 2150) $PN 98
J 2
(1240 2160);
DISPLAY 0.617021 (1240 2160);
PAINT ORANGE (1240 2160);
FORCEPROP 2 LASTPIN (1250 2100) $PN 101
J 2
(1240 2110);
DISPLAY 0.617021 (1240 2110);
PAINT ORANGE (1240 2110);
FORCEPROP 2 LASTPIN (1250 2050) $PN 103
J 2
(1240 2060);
DISPLAY 0.617021 (1240 2060);
PAINT ORANGE (1240 2060);
FORCEPROP 2 LASTPIN (1250 2000) $PN 105
J 2
(1240 2010);
DISPLAY 0.617021 (1240 2010);
PAINT ORANGE (1240 2010);
FORCEPROP 2 LASTPIN (1250 1950) $PN 107
J 2
(1240 1960);
DISPLAY 0.617021 (1240 1960);
PAINT ORANGE (1240 1960);
FORCEPROP 2 LASTPIN (1250 1900) $PN 109
J 2
(1240 1910);
DISPLAY 0.617021 (1240 1910);
PAINT ORANGE (1240 1910);
FORCEPROP 2 LASTPIN (1250 1850) $PN 112
J 2
(1240 1860);
DISPLAY 0.617021 (1240 1860);
PAINT ORANGE (1240 1860);
FORCEPROP 2 LASTPIN (1250 1800) $PN 114
J 2
(1240 1810);
DISPLAY 0.617021 (1240 1810);
PAINT ORANGE (1240 1810);
FORCEPROP 2 LASTPIN (1250 1750) $PN 116
J 2
(1240 1760);
DISPLAY 0.617021 (1240 1760);
PAINT ORANGE (1240 1760);
FORCEPROP 2 LASTPIN (1250 1700) $PN 118
J 2
(1240 1710);
DISPLAY 0.617021 (1240 1710);
PAINT ORANGE (1240 1710);
FORCEPROP 2 LASTPIN (1250 1650) $PN 120
J 2
(1240 1660);
DISPLAY 0.617021 (1240 1660);
PAINT ORANGE (1240 1660);
FORCEPROP 2 LASTPIN (1250 1600) $PN 123
J 2
(1240 1610);
DISPLAY 0.617021 (1240 1610);
PAINT ORANGE (1240 1610);
FORCEPROP 2 LASTPIN (1250 1550) $PN 125
J 2
(1240 1560);
DISPLAY 0.617021 (1240 1560);
PAINT ORANGE (1240 1560);
FORCEPROP 2 LASTPIN (1250 1500) $PN 127
J 2
(1240 1510);
DISPLAY 0.617021 (1240 1510);
PAINT ORANGE (1240 1510);
FORCEPROP 2 LASTPIN (1250 1450) $PN 129
J 2
(1240 1460);
DISPLAY 0.617021 (1240 1460);
PAINT ORANGE (1240 1460);
FORCEPROP 2 LASTPIN (1250 1400) $PN 131
J 2
(1240 1410);
DISPLAY 0.617021 (1240 1410);
PAINT ORANGE (1240 1410);
FORCEPROP 2 LASTPIN (1250 1350) $PN 134
J 2
(1240 1360);
DISPLAY 0.617021 (1240 1360);
PAINT ORANGE (1240 1360);
FORCEPROP 2 LASTPIN (1250 1300) $PN 136
J 2
(1240 1310);
DISPLAY 0.617021 (1240 1310);
PAINT ORANGE (1240 1310);
FORCEPROP 2 LASTPIN (1250 1250) $PN 138
J 2
(1240 1260);
DISPLAY 0.617021 (1240 1260);
PAINT ORANGE (1240 1260);
FORCEPROP 2 LASTPIN (2250 3550) $PN 147
J 0
(2260 3560);
DISPLAY 0.617021 (2260 3560);
PAINT ORANGE (2260 3560);
FORCEPROP 2 LASTPIN (2250 3500) $PN 149
J 0
(2260 3510);
DISPLAY 0.617021 (2260 3510);
PAINT ORANGE (2260 3510);
FORCEPROP 2 LASTPIN (2250 3450) $PN 151
J 0
(2260 3460);
DISPLAY 0.617021 (2260 3460);
PAINT ORANGE (2260 3460);
FORCEPROP 2 LASTPIN (2250 3400) $PN 154
J 0
(2260 3410);
DISPLAY 0.617021 (2260 3410);
PAINT ORANGE (2260 3410);
FORCEPROP 2 LASTPIN (2250 3350) $PN 156
J 0
(2260 3360);
DISPLAY 0.617021 (2260 3360);
PAINT ORANGE (2260 3360);
FORCEPROP 2 LASTPIN (2250 3300) $PN 158
J 0
(2260 3310);
DISPLAY 0.617021 (2260 3310);
PAINT ORANGE (2260 3310);
FORCEPROP 2 LASTPIN (2250 3250) $PN 160
J 0
(2260 3260);
DISPLAY 0.617021 (2260 3260);
PAINT ORANGE (2260 3260);
FORCEPROP 2 LASTPIN (2250 3200) $PN 162
J 0
(2260 3210);
DISPLAY 0.617021 (2260 3210);
PAINT ORANGE (2260 3210);
FORCEPROP 2 LASTPIN (2250 3150) $PN 165
J 0
(2260 3160);
DISPLAY 0.617021 (2260 3160);
PAINT ORANGE (2260 3160);
FORCEPROP 2 LASTPIN (2250 3100) $PN 167
J 0
(2260 3110);
DISPLAY 0.617021 (2260 3110);
PAINT ORANGE (2260 3110);
FORCEPROP 2 LASTPIN (2250 3050) $PN 169
J 0
(2260 3060);
DISPLAY 0.617021 (2260 3060);
PAINT ORANGE (2260 3060);
FORCEPROP 2 LASTPIN (2250 3000) $PN 171
J 0
(2260 3010);
DISPLAY 0.617021 (2260 3010);
PAINT ORANGE (2260 3010);
FORCEPROP 2 LASTPIN (2250 2950) $PN 173
J 0
(2260 2960);
DISPLAY 0.617021 (2260 2960);
PAINT ORANGE (2260 2960);
FORCEPROP 2 LASTPIN (2250 2900) $PN 176
J 0
(2260 2910);
DISPLAY 0.617021 (2260 2910);
PAINT ORANGE (2260 2910);
FORCEPROP 2 LASTPIN (2250 2850) $PN 178
J 0
(2260 2860);
DISPLAY 0.617021 (2260 2860);
PAINT ORANGE (2260 2860);
FORCEPROP 2 LASTPIN (2250 2800) $PN 180
J 0
(2260 2810);
DISPLAY 0.617021 (2260 2810);
PAINT ORANGE (2260 2810);
FORCEPROP 2 LASTPIN (2250 2750) $PN 182
J 0
(2260 2760);
DISPLAY 0.617021 (2260 2760);
PAINT ORANGE (2260 2760);
FORCEPROP 2 LASTPIN (2250 2700) $PN 184
J 0
(2260 2710);
DISPLAY 0.617021 (2260 2710);
PAINT ORANGE (2260 2710);
FORCEPROP 2 LASTPIN (2250 2650) $PN 187
J 0
(2260 2660);
DISPLAY 0.617021 (2260 2660);
PAINT ORANGE (2260 2660);
FORCEPROP 2 LASTPIN (2250 2600) $PN 189
J 0
(2260 2610);
DISPLAY 0.617021 (2260 2610);
PAINT ORANGE (2260 2610);
FORCEPROP 2 LASTPIN (2250 2550) $PN 191
J 0
(2260 2560);
DISPLAY 0.617021 (2260 2560);
PAINT ORANGE (2260 2560);
FORCEPROP 2 LASTPIN (2250 2500) $PN 193
J 0
(2260 2510);
DISPLAY 0.617021 (2260 2510);
PAINT ORANGE (2260 2510);
FORCEPROP 2 LASTPIN (2250 2450) $PN 195
J 0
(2260 2460);
DISPLAY 0.617021 (2260 2460);
PAINT ORANGE (2260 2460);
FORCEPROP 2 LASTPIN (2250 2400) $PN 198
J 0
(2260 2410);
DISPLAY 0.617021 (2260 2410);
PAINT ORANGE (2260 2410);
FORCEPROP 2 LASTPIN (2250 2350) $PN 200
J 0
(2260 2360);
DISPLAY 0.617021 (2260 2360);
PAINT ORANGE (2260 2360);
FORCEPROP 2 LASTPIN (2250 2300) $PN 202
J 0
(2260 2310);
DISPLAY 0.617021 (2260 2310);
PAINT ORANGE (2260 2310);
FORCEPROP 2 LASTPIN (2250 2250) $PN 239
J 0
(2260 2260);
DISPLAY 0.617021 (2260 2260);
PAINT ORANGE (2260 2260);
FORCEPROP 2 LASTPIN (2250 2200) $PN 241
J 0
(2260 2210);
DISPLAY 0.617021 (2260 2210);
PAINT ORANGE (2260 2210);
FORCEPROP 2 LASTPIN (2250 2150) $PN 243
J 0
(2260 2160);
DISPLAY 0.617021 (2260 2160);
PAINT ORANGE (2260 2160);
FORCEPROP 2 LASTPIN (2250 2100) $PN 246
J 0
(2260 2110);
DISPLAY 0.617021 (2260 2110);
PAINT ORANGE (2260 2110);
FORCEPROP 2 LASTPIN (2250 2050) $PN 248
J 0
(2260 2060);
DISPLAY 0.617021 (2260 2060);
PAINT ORANGE (2260 2060);
FORCEPROP 2 LASTPIN (2250 2000) $PN 250
J 0
(2260 2010);
DISPLAY 0.617021 (2260 2010);
PAINT ORANGE (2260 2010);
FORCEPROP 2 LASTPIN (2250 1950) $PN 252
J 0
(2260 1960);
DISPLAY 0.617021 (2260 1960);
PAINT ORANGE (2260 1960);
FORCEPROP 2 LASTPIN (2250 1900) $PN 254
J 0
(2260 1910);
DISPLAY 0.617021 (2260 1910);
PAINT ORANGE (2260 1910);
FORCEPROP 2 LASTPIN (2250 1850) $PN 257
J 0
(2260 1860);
DISPLAY 0.617021 (2260 1860);
PAINT ORANGE (2260 1860);
FORCEPROP 2 LASTPIN (2250 1800) $PN 259
J 0
(2260 1810);
DISPLAY 0.617021 (2260 1810);
PAINT ORANGE (2260 1810);
FORCEPROP 2 LASTPIN (2250 1750) $PN 261
J 0
(2260 1760);
DISPLAY 0.617021 (2260 1760);
PAINT ORANGE (2260 1760);
FORCEPROP 2 LASTPIN (2250 1700) $PN 263
J 0
(2260 1710);
DISPLAY 0.617021 (2260 1710);
PAINT ORANGE (2260 1710);
FORCEPROP 2 LASTPIN (2250 1650) $PN 265
J 0
(2260 1660);
DISPLAY 0.617021 (2260 1660);
PAINT ORANGE (2260 1660);
FORCEPROP 2 LASTPIN (2250 1600) $PN 268
J 0
(2260 1610);
DISPLAY 0.617021 (2260 1610);
PAINT ORANGE (2260 1610);
FORCEPROP 2 LASTPIN (2250 1550) $PN 270
J 0
(2260 1560);
DISPLAY 0.617021 (2260 1560);
PAINT ORANGE (2260 1560);
FORCEPROP 2 LASTPIN (2250 1500) $PN 272
J 0
(2260 1510);
DISPLAY 0.617021 (2260 1510);
PAINT ORANGE (2260 1510);
FORCEPROP 2 LASTPIN (2250 1450) $PN 274
J 0
(2260 1460);
DISPLAY 0.617021 (2260 1460);
PAINT ORANGE (2260 1460);
FORCEPROP 2 LASTPIN (2250 1400) $PN 276
J 0
(2260 1410);
DISPLAY 0.617021 (2260 1410);
PAINT ORANGE (2260 1410);
FORCEPROP 2 LASTPIN (2250 1350) $PN 279
J 0
(2260 1360);
DISPLAY 0.617021 (2260 1360);
PAINT ORANGE (2260 1360);
FORCEPROP 2 LASTPIN (2250 1300) $PN 281
J 0
(2260 1310);
DISPLAY 0.617021 (2260 1310);
PAINT ORANGE (2260 1310);
FORCEPROP 2 LASTPIN (2250 1250) $PN 283
J 0
(2260 1260);
DISPLAY 0.617021 (2260 1260);
PAINT ORANGE (2260 1260);
FORCEPROP 1 LAST PACK_TYPE PIP
J 0
(1300 3850);
PAINT SKYBLUE (1300 3850);
DISPLAY INVISIBLE (1300 3850);
FORCEPROP 2 LAST BOM_COST MEM
J 0
(1750 2400);
PAINT ORANGE (1750 2400);
DISPLAY INVISIBLE (1750 2400);
FORCEPROP 2 LAST CDS_LIB mstr_sconn
J 0
(1750 2400);
PAINT ORANGE (1750 2400);
DISPLAY INVISIBLE (1750 2400);
FORCEPROP 2 LAST SEC_TYPE PIP
J 0
(1300 3850);
DISPLAY 1.021277 (1300 3850);
PAINT ORANGE (1300 3850);
DISPLAY INVISIBLE (1300 3850);
FORCEPROP 2 LAST SEC 3
J 0
(1300 3850);
DISPLAY 0.680851 (1300 3850);
PAINT MONO (1300 3850);
DISPLAY INVISIBLE (1300 3850);
FORCEPROP 2 LAST CDS_LOCATION J1G3
J 0
(1300 3800);
DISPLAY 0.617021 (1300 3800);
PAINT AQUA (1300 3800);
DISPLAY INVISIBLE (1300 3800);
FORCEPROP 1 LAST PATH I185
J 0
(1750 3750);
PAINT GREEN (1750 3750);
DISPLAY INVISIBLE (1750 3750);
FORCEPROP 2 LAST ROOM DDR4_CH_J
J 0
(1750 2400);
PAINT ORANGE (1750 2400);
DISPLAY INVISIBLE (1750 2400);
FORCEADD SCONN288_H44441004..1
(-2550 3150);
FORCEPROP 1 LAST LOCATION J1G3
J 0
(-3000 5050);
DISPLAY 0.617021 (-3000 5050);
PAINT AQUA (-3000 5050);
FORCEPROP 1 LAST PART_NUMBER H44441-004
J 0
(-3000 1150);
DISPLAY 0.617021 (-3000 1150);
PAINT BLUE (-3000 1150);
FORCEPROP 1 LAST MATERIAL SCONN
J 0
(-3000 5000);
DISPLAY 0.617021 (-3000 5000);
PAINT SKYBLUE (-3000 5000);
FORCEPROP 2 LASTPIN (-3050 1650) $PN 146
J 2
(-3060 1660);
DISPLAY 0.617021 (-3060 1660);
PAINT ORANGE (-3060 1660);
FORCEPROP 2 LASTPIN (-3050 2000) $PN 284
J 2
(-3060 2010);
DISPLAY 0.617021 (-3060 2010);
PAINT ORANGE (-3060 2010);
FORCEPROP 2 LASTPIN (-3050 1800) $PN 285
J 2
(-3060 1810);
DISPLAY 0.617021 (-3060 1810);
PAINT ORANGE (-3060 1810);
FORCEPROP 2 LASTPIN (-3050 1750) $PN 141
J 2
(-3060 1760);
DISPLAY 0.617021 (-3060 1760);
PAINT ORANGE (-3060 1760);
FORCEPROP 2 LASTPIN (-3050 1350) $PN 230
J 2
(-3060 1360);
DISPLAY 0.617021 (-3060 1360);
PAINT ORANGE (-3060 1360);
FORCEPROP 2 LASTPIN (-3050 1950) $PN 238
J 2
(-3060 1960);
DISPLAY 0.617021 (-3060 1960);
PAINT ORANGE (-3060 1960);
FORCEPROP 2 LASTPIN (-3050 1900) $PN 140
J 2
(-3060 1910);
DISPLAY 0.617021 (-3060 1910);
PAINT ORANGE (-3060 1910);
FORCEPROP 2 LASTPIN (-3050 1850) $PN 139
J 2
(-3060 1860);
DISPLAY 0.617021 (-3060 1860);
PAINT ORANGE (-3060 1860);
FORCEPROP 2 LASTPIN (-3050 3300) $PN 237
J 2
(-3060 3310);
DISPLAY 0.617021 (-3060 3310);
PAINT ORANGE (-3060 3310);
FORCEPROP 2 LASTPIN (-3050 3250) $PN 93
J 2
(-3060 3260);
DISPLAY 0.617021 (-3060 3260);
PAINT ORANGE (-3060 3260);
FORCEPROP 2 LASTPIN (-3050 3200) $PN 89
J 2
(-3060 3210);
DISPLAY 0.617021 (-3060 3210);
PAINT ORANGE (-3060 3210);
FORCEPROP 2 LASTPIN (-3050 3150) $PN 84
J 2
(-3060 3160);
DISPLAY 0.617021 (-3060 3160);
PAINT ORANGE (-3060 3160);
FORCEPROP 2 LASTPIN (-3050 1550) $PN 144
J 2
(-3060 1560);
DISPLAY 0.617021 (-3060 1560);
PAINT ORANGE (-3060 1560);
FORCEPROP 2 LASTPIN (-3050 1500) $PN 227
J 2
(-3060 1510);
DISPLAY 0.617021 (-3060 1510);
PAINT ORANGE (-3060 1510);
FORCEPROP 2 LASTPIN (-3050 1450) $PN 205
J 2
(-3060 1460);
DISPLAY 0.617021 (-3060 1460);
PAINT ORANGE (-3060 1460);
FORCEPROP 2 LASTPIN (-3050 2250) $PN 58
J 2
(-3060 2260);
DISPLAY 0.617021 (-3060 2260);
PAINT ORANGE (-3060 2260);
FORCEPROP 2 LASTPIN (-3050 2300) $PN 222
J 2
(-3060 2310);
DISPLAY 0.617021 (-3060 2310);
PAINT ORANGE (-3060 2310);
FORCEPROP 2 LASTPIN (-3050 2900) $PN 91
J 2
(-3060 2910);
DISPLAY 0.617021 (-3060 2910);
PAINT ORANGE (-3060 2910);
FORCEPROP 2 LASTPIN (-3050 2850) $PN 87
J 2
(-3060 2860);
DISPLAY 0.617021 (-3060 2860);
PAINT ORANGE (-3060 2860);
FORCEPROP 2 LASTPIN (-3050 2200) $PN 78
J 2
(-3060 2210);
DISPLAY 0.617021 (-3060 2210);
PAINT ORANGE (-3060 2210);
FORCEPROP 2 LASTPIN (-2050 4800) $PN 280
J 0
(-2040 4810);
DISPLAY 0.617021 (-2040 4810);
PAINT ORANGE (-2040 4810);
FORCEPROP 2 LASTPIN (-2050 4750) $PN 135
J 0
(-2040 4760);
DISPLAY 0.617021 (-2040 4760);
PAINT ORANGE (-2040 4760);
FORCEPROP 2 LASTPIN (-2050 4700) $PN 273
J 0
(-2040 4710);
DISPLAY 0.617021 (-2040 4710);
PAINT ORANGE (-2040 4710);
FORCEPROP 2 LASTPIN (-2050 4650) $PN 128
J 0
(-2040 4660);
DISPLAY 0.617021 (-2040 4660);
PAINT ORANGE (-2040 4660);
FORCEPROP 2 LASTPIN (-2050 4600) $PN 282
J 0
(-2040 4610);
DISPLAY 0.617021 (-2040 4610);
PAINT ORANGE (-2040 4610);
FORCEPROP 2 LASTPIN (-2050 4550) $PN 137
J 0
(-2040 4560);
DISPLAY 0.617021 (-2040 4560);
PAINT ORANGE (-2040 4560);
FORCEPROP 2 LASTPIN (-2050 4500) $PN 275
J 0
(-2040 4510);
DISPLAY 0.617021 (-2040 4510);
PAINT ORANGE (-2040 4510);
FORCEPROP 2 LASTPIN (-2050 4450) $PN 130
J 0
(-2040 4460);
DISPLAY 0.617021 (-2040 4460);
PAINT ORANGE (-2040 4460);
FORCEPROP 2 LASTPIN (-2050 4400) $PN 269
J 0
(-2040 4410);
DISPLAY 0.617021 (-2040 4410);
PAINT ORANGE (-2040 4410);
FORCEPROP 2 LASTPIN (-2050 4350) $PN 124
J 0
(-2040 4360);
DISPLAY 0.617021 (-2040 4360);
PAINT ORANGE (-2040 4360);
FORCEPROP 2 LASTPIN (-2050 4300) $PN 262
J 0
(-2040 4310);
DISPLAY 0.617021 (-2040 4310);
PAINT ORANGE (-2040 4310);
FORCEPROP 2 LASTPIN (-2050 4250) $PN 117
J 0
(-2040 4260);
DISPLAY 0.617021 (-2040 4260);
PAINT ORANGE (-2040 4260);
FORCEPROP 2 LASTPIN (-2050 4200) $PN 271
J 0
(-2040 4210);
DISPLAY 0.617021 (-2040 4210);
PAINT ORANGE (-2040 4210);
FORCEPROP 2 LASTPIN (-2050 4150) $PN 126
J 0
(-2040 4160);
DISPLAY 0.617021 (-2040 4160);
PAINT ORANGE (-2040 4160);
FORCEPROP 2 LASTPIN (-2050 4100) $PN 264
J 0
(-2040 4110);
DISPLAY 0.617021 (-2040 4110);
PAINT ORANGE (-2040 4110);
FORCEPROP 2 LASTPIN (-2050 4050) $PN 119
J 0
(-2040 4060);
DISPLAY 0.617021 (-2040 4060);
PAINT ORANGE (-2040 4060);
FORCEPROP 2 LASTPIN (-2050 4000) $PN 258
J 0
(-2040 4010);
DISPLAY 0.617021 (-2040 4010);
PAINT ORANGE (-2040 4010);
FORCEPROP 2 LASTPIN (-2050 3950) $PN 113
J 0
(-2040 3960);
DISPLAY 0.617021 (-2040 3960);
PAINT ORANGE (-2040 3960);
FORCEPROP 2 LASTPIN (-2050 3900) $PN 251
J 0
(-2040 3910);
DISPLAY 0.617021 (-2040 3910);
PAINT ORANGE (-2040 3910);
FORCEPROP 2 LASTPIN (-2050 3850) $PN 106
J 0
(-2040 3860);
DISPLAY 0.617021 (-2040 3860);
PAINT ORANGE (-2040 3860);
FORCEPROP 2 LASTPIN (-2050 3800) $PN 260
J 0
(-2040 3810);
DISPLAY 0.617021 (-2040 3810);
PAINT ORANGE (-2040 3810);
FORCEPROP 2 LASTPIN (-2050 3750) $PN 115
J 0
(-2040 3760);
DISPLAY 0.617021 (-2040 3760);
PAINT ORANGE (-2040 3760);
FORCEPROP 2 LASTPIN (-2050 3700) $PN 253
J 0
(-2040 3710);
DISPLAY 0.617021 (-2040 3710);
PAINT ORANGE (-2040 3710);
FORCEPROP 2 LASTPIN (-2050 3650) $PN 108
J 0
(-2040 3660);
DISPLAY 0.617021 (-2040 3660);
PAINT ORANGE (-2040 3660);
FORCEPROP 2 LASTPIN (-2050 3600) $PN 247
J 0
(-2040 3610);
DISPLAY 0.617021 (-2040 3610);
PAINT ORANGE (-2040 3610);
FORCEPROP 2 LASTPIN (-2050 3550) $PN 102
J 0
(-2040 3560);
DISPLAY 0.617021 (-2040 3560);
PAINT ORANGE (-2040 3560);
FORCEPROP 2 LASTPIN (-2050 3500) $PN 240
J 0
(-2040 3510);
DISPLAY 0.617021 (-2040 3510);
PAINT ORANGE (-2040 3510);
FORCEPROP 2 LASTPIN (-2050 3450) $PN 95
J 0
(-2040 3460);
DISPLAY 0.617021 (-2040 3460);
PAINT ORANGE (-2040 3460);
FORCEPROP 2 LASTPIN (-2050 3400) $PN 249
J 0
(-2040 3410);
DISPLAY 0.617021 (-2040 3410);
PAINT ORANGE (-2040 3410);
FORCEPROP 2 LASTPIN (-2050 3350) $PN 104
J 0
(-2040 3360);
DISPLAY 0.617021 (-2040 3360);
PAINT ORANGE (-2040 3360);
FORCEPROP 2 LASTPIN (-2050 3300) $PN 242
J 0
(-2040 3310);
DISPLAY 0.617021 (-2040 3310);
PAINT ORANGE (-2040 3310);
FORCEPROP 2 LASTPIN (-2050 3250) $PN 97
J 0
(-2040 3260);
DISPLAY 0.617021 (-2040 3260);
PAINT ORANGE (-2040 3260);
FORCEPROP 2 LASTPIN (-2050 3200) $PN 188
J 0
(-2040 3210);
DISPLAY 0.617021 (-2040 3210);
PAINT ORANGE (-2040 3210);
FORCEPROP 2 LASTPIN (-2050 3150) $PN 43
J 0
(-2040 3160);
DISPLAY 0.617021 (-2040 3160);
PAINT ORANGE (-2040 3160);
FORCEPROP 2 LASTPIN (-2050 3100) $PN 181
J 0
(-2040 3110);
DISPLAY 0.617021 (-2040 3110);
PAINT ORANGE (-2040 3110);
FORCEPROP 2 LASTPIN (-2050 3050) $PN 36
J 0
(-2040 3060);
DISPLAY 0.617021 (-2040 3060);
PAINT ORANGE (-2040 3060);
FORCEPROP 2 LASTPIN (-2050 3000) $PN 190
J 0
(-2040 3010);
DISPLAY 0.617021 (-2040 3010);
PAINT ORANGE (-2040 3010);
FORCEPROP 2 LASTPIN (-2050 2950) $PN 45
J 0
(-2040 2960);
DISPLAY 0.617021 (-2040 2960);
PAINT ORANGE (-2040 2960);
FORCEPROP 2 LASTPIN (-2050 2900) $PN 183
J 0
(-2040 2910);
DISPLAY 0.617021 (-2040 2910);
PAINT ORANGE (-2040 2910);
FORCEPROP 2 LASTPIN (-2050 2850) $PN 38
J 0
(-2040 2860);
DISPLAY 0.617021 (-2040 2860);
PAINT ORANGE (-2040 2860);
FORCEPROP 2 LASTPIN (-2050 2800) $PN 177
J 0
(-2040 2810);
DISPLAY 0.617021 (-2040 2810);
PAINT ORANGE (-2040 2810);
FORCEPROP 2 LASTPIN (-2050 2750) $PN 32
J 0
(-2040 2760);
DISPLAY 0.617021 (-2040 2760);
PAINT ORANGE (-2040 2760);
FORCEPROP 2 LASTPIN (-2050 2700) $PN 170
J 0
(-2040 2710);
DISPLAY 0.617021 (-2040 2710);
PAINT ORANGE (-2040 2710);
FORCEPROP 2 LASTPIN (-2050 2650) $PN 25
J 0
(-2040 2660);
DISPLAY 0.617021 (-2040 2660);
PAINT ORANGE (-2040 2660);
FORCEPROP 2 LASTPIN (-2050 2600) $PN 179
J 0
(-2040 2610);
DISPLAY 0.617021 (-2040 2610);
PAINT ORANGE (-2040 2610);
FORCEPROP 2 LASTPIN (-2050 2550) $PN 34
J 0
(-2040 2560);
DISPLAY 0.617021 (-2040 2560);
PAINT ORANGE (-2040 2560);
FORCEPROP 2 LASTPIN (-2050 2500) $PN 172
J 0
(-2040 2510);
DISPLAY 0.617021 (-2040 2510);
PAINT ORANGE (-2040 2510);
FORCEPROP 2 LASTPIN (-2050 2450) $PN 27
J 0
(-2040 2460);
DISPLAY 0.617021 (-2040 2460);
PAINT ORANGE (-2040 2460);
FORCEPROP 2 LASTPIN (-2050 2400) $PN 166
J 0
(-2040 2410);
DISPLAY 0.617021 (-2040 2410);
PAINT ORANGE (-2040 2410);
FORCEPROP 2 LASTPIN (-2050 2350) $PN 21
J 0
(-2040 2360);
DISPLAY 0.617021 (-2040 2360);
PAINT ORANGE (-2040 2360);
FORCEPROP 2 LASTPIN (-2050 2300) $PN 159
J 0
(-2040 2310);
DISPLAY 0.617021 (-2040 2310);
PAINT ORANGE (-2040 2310);
FORCEPROP 2 LASTPIN (-2050 2250) $PN 14
J 0
(-2040 2260);
DISPLAY 0.617021 (-2040 2260);
PAINT ORANGE (-2040 2260);
FORCEPROP 2 LASTPIN (-2050 2200) $PN 168
J 0
(-2040 2210);
DISPLAY 0.617021 (-2040 2210);
PAINT ORANGE (-2040 2210);
FORCEPROP 2 LASTPIN (-2050 2150) $PN 23
J 0
(-2040 2160);
DISPLAY 0.617021 (-2040 2160);
PAINT ORANGE (-2040 2160);
FORCEPROP 2 LASTPIN (-2050 2100) $PN 161
J 0
(-2040 2110);
DISPLAY 0.617021 (-2040 2110);
PAINT ORANGE (-2040 2110);
FORCEPROP 2 LASTPIN (-2050 2050) $PN 16
J 0
(-2040 2060);
DISPLAY 0.617021 (-2040 2060);
PAINT ORANGE (-2040 2060);
FORCEPROP 2 LASTPIN (-2050 2000) $PN 155
J 0
(-2040 2010);
DISPLAY 0.617021 (-2040 2010);
PAINT ORANGE (-2040 2010);
FORCEPROP 2 LASTPIN (-2050 1950) $PN 10
J 0
(-2040 1960);
DISPLAY 0.617021 (-2040 1960);
PAINT ORANGE (-2040 1960);
FORCEPROP 2 LASTPIN (-2050 1900) $PN 148
J 0
(-2040 1910);
DISPLAY 0.617021 (-2040 1910);
PAINT ORANGE (-2040 1910);
FORCEPROP 2 LASTPIN (-2050 1850) $PN 3
J 0
(-2040 1860);
DISPLAY 0.617021 (-2040 1860);
PAINT ORANGE (-2040 1860);
FORCEPROP 2 LASTPIN (-2050 1800) $PN 157
J 0
(-2040 1810);
DISPLAY 0.617021 (-2040 1810);
PAINT ORANGE (-2040 1810);
FORCEPROP 2 LASTPIN (-2050 1750) $PN 12
J 0
(-2040 1760);
DISPLAY 0.617021 (-2040 1760);
PAINT ORANGE (-2040 1760);
FORCEPROP 2 LASTPIN (-2050 1700) $PN 150
J 0
(-2040 1710);
DISPLAY 0.617021 (-2040 1710);
PAINT ORANGE (-2040 1710);
FORCEPROP 2 LASTPIN (-2050 1650) $PN 5
J 0
(-2040 1660);
DISPLAY 0.617021 (-2040 1660);
PAINT ORANGE (-2040 1660);
FORCEPROP 2 LASTPIN (-3050 3050) $PN 203
J 2
(-3060 3060);
DISPLAY 0.617021 (-3060 3060);
PAINT ORANGE (-3060 3060);
FORCEPROP 2 LASTPIN (-3050 3000) $PN 60
J 2
(-3060 3010);
DISPLAY 0.617021 (-3060 3010);
PAINT ORANGE (-3060 3010);
FORCEPROP 2 LASTPIN (-3050 3600) $PN 218
J 2
(-3060 3610);
DISPLAY 0.617021 (-3060 3610);
PAINT ORANGE (-3060 3610);
FORCEPROP 2 LASTPIN (-3050 3550) $PN 219
J 2
(-3060 3560);
DISPLAY 0.617021 (-3060 3560);
PAINT ORANGE (-3060 3560);
FORCEPROP 2 LASTPIN (-3050 3500) $PN 74
J 2
(-3060 3510);
DISPLAY 0.617021 (-3060 3510);
PAINT ORANGE (-3060 3510);
FORCEPROP 2 LASTPIN (-3050 3450) $PN 75
J 2
(-3060 3460);
DISPLAY 0.617021 (-3060 3460);
PAINT ORANGE (-3060 3460);
FORCEPROP 2 LASTPIN (-3050 2750) $PN 199
J 2
(-3060 2760);
DISPLAY 0.617021 (-3060 2760);
PAINT ORANGE (-3060 2760);
FORCEPROP 2 LASTPIN (-3050 2700) $PN 54
J 2
(-3060 2710);
DISPLAY 0.617021 (-3060 2710);
PAINT ORANGE (-3060 2710);
FORCEPROP 2 LASTPIN (-3050 2650) $PN 192
J 2
(-3060 2660);
DISPLAY 0.617021 (-3060 2660);
PAINT ORANGE (-3060 2660);
FORCEPROP 2 LASTPIN (-3050 2600) $PN 47
J 2
(-3060 2610);
DISPLAY 0.617021 (-3060 2610);
PAINT ORANGE (-3060 2610);
FORCEPROP 2 LASTPIN (-3050 2550) $PN 201
J 2
(-3060 2560);
DISPLAY 0.617021 (-3060 2560);
PAINT ORANGE (-3060 2560);
FORCEPROP 2 LASTPIN (-3050 2500) $PN 56
J 2
(-3060 2510);
DISPLAY 0.617021 (-3060 2510);
PAINT ORANGE (-3060 2510);
FORCEPROP 2 LASTPIN (-3050 2450) $PN 194
J 2
(-3060 2460);
DISPLAY 0.617021 (-3060 2460);
PAINT ORANGE (-3060 2460);
FORCEPROP 2 LASTPIN (-3050 2400) $PN 49
J 2
(-3060 2410);
DISPLAY 0.617021 (-3060 2410);
PAINT ORANGE (-3060 2410);
FORCEPROP 2 LASTPIN (-3050 3350) $PN 235
J 2
(-3060 3360);
DISPLAY 0.617021 (-3060 3360);
PAINT ORANGE (-3060 3360);
FORCEPROP 2 LASTPIN (-3050 3750) $PN 207
J 2
(-3060 3760);
DISPLAY 0.617021 (-3060 3760);
PAINT ORANGE (-3060 3760);
FORCEPROP 2 LASTPIN (-3050 3700) $PN 63
J 2
(-3060 3710);
DISPLAY 0.617021 (-3060 3710);
PAINT ORANGE (-3060 3710);
FORCEPROP 2 LASTPIN (-3050 3850) $PN 224
J 2
(-3060 3860);
DISPLAY 0.617021 (-3060 3860);
PAINT ORANGE (-3060 3860);
FORCEPROP 2 LASTPIN (-3050 3800) $PN 81
J 2
(-3060 3810);
DISPLAY 0.617021 (-3060 3810);
PAINT ORANGE (-3060 3810);
FORCEPROP 2 LASTPIN (-3050 2150) $PN 208
J 2
(-3060 2160);
DISPLAY 0.617021 (-3060 2160);
PAINT ORANGE (-3060 2160);
FORCEPROP 2 LASTPIN (-3050 2100) $PN 62
J 2
(-3060 2110);
DISPLAY 0.617021 (-3060 2110);
PAINT ORANGE (-3060 2110);
FORCEPROP 2 LASTPIN (-3050 4800) $PN 234
J 2
(-3060 4810);
DISPLAY 0.617021 (-3060 4810);
PAINT ORANGE (-3060 4810);
FORCEPROP 2 LASTPIN (-3050 4750) $PN 82
J 2
(-3060 4760);
DISPLAY 0.617021 (-3060 4760);
PAINT ORANGE (-3060 4760);
FORCEPROP 2 LASTPIN (-3050 4700) $PN 86
J 2
(-3060 4710);
DISPLAY 0.617021 (-3060 4710);
PAINT ORANGE (-3060 4710);
FORCEPROP 2 LASTPIN (-3050 4650) $PN 228
J 2
(-3060 4660);
DISPLAY 0.617021 (-3060 4660);
PAINT ORANGE (-3060 4660);
FORCEPROP 2 LASTPIN (-3050 4600) $PN 232
J 2
(-3060 4610);
DISPLAY 0.617021 (-3060 4610);
PAINT ORANGE (-3060 4610);
FORCEPROP 2 LASTPIN (-3050 4550) $PN 65
J 2
(-3060 4560);
DISPLAY 0.617021 (-3060 4560);
PAINT ORANGE (-3060 4560);
FORCEPROP 2 LASTPIN (-3050 4500) $PN 210
J 2
(-3060 4510);
DISPLAY 0.617021 (-3060 4510);
PAINT ORANGE (-3060 4510);
FORCEPROP 2 LASTPIN (-3050 4450) $PN 225
J 2
(-3060 4460);
DISPLAY 0.617021 (-3060 4460);
PAINT ORANGE (-3060 4460);
FORCEPROP 2 LASTPIN (-3050 4400) $PN 66
J 2
(-3060 4410);
DISPLAY 0.617021 (-3060 4410);
PAINT ORANGE (-3060 4410);
FORCEPROP 2 LASTPIN (-3050 4350) $PN 68
J 2
(-3060 4360);
DISPLAY 0.617021 (-3060 4360);
PAINT ORANGE (-3060 4360);
FORCEPROP 2 LASTPIN (-3050 4300) $PN 211
J 2
(-3060 4310);
DISPLAY 0.617021 (-3060 4310);
PAINT ORANGE (-3060 4310);
FORCEPROP 2 LASTPIN (-3050 4250) $PN 69
J 2
(-3060 4260);
DISPLAY 0.617021 (-3060 4260);
PAINT ORANGE (-3060 4260);
FORCEPROP 2 LASTPIN (-3050 4200) $PN 213
J 2
(-3060 4210);
DISPLAY 0.617021 (-3060 4210);
PAINT ORANGE (-3060 4210);
FORCEPROP 2 LASTPIN (-3050 4150) $PN 214
J 2
(-3060 4160);
DISPLAY 0.617021 (-3060 4160);
PAINT ORANGE (-3060 4160);
FORCEPROP 2 LASTPIN (-3050 4100) $PN 71
J 2
(-3060 4110);
DISPLAY 0.617021 (-3060 4110);
PAINT ORANGE (-3060 4110);
FORCEPROP 2 LASTPIN (-3050 4050) $PN 216
J 2
(-3060 4060);
DISPLAY 0.617021 (-3060 4060);
PAINT ORANGE (-3060 4060);
FORCEPROP 2 LASTPIN (-3050 4000) $PN 72
J 2
(-3060 4010);
DISPLAY 0.617021 (-3060 4010);
PAINT ORANGE (-3060 4010);
FORCEPROP 2 LASTPIN (-3050 3950) $PN 79
J 2
(-3060 3960);
DISPLAY 0.617021 (-3060 3960);
PAINT ORANGE (-3060 3960);
FORCEPROP 1 LAST PACK_TYPE PIP
J 0
(-3000 5100);
PAINT SKYBLUE (-3000 5100);
DISPLAY INVISIBLE (-3000 5100);
FORCEPROP 2 LAST BOM_COST MEM
J 0
(-2550 3150);
PAINT ORANGE (-2550 3150);
DISPLAY INVISIBLE (-2550 3150);
FORCEPROP 2 LAST CDS_LIB mstr_sconn
J 0
(-2550 3150);
PAINT ORANGE (-2550 3150);
DISPLAY INVISIBLE (-2550 3150);
FORCEPROP 2 LAST SEC_TYPE PIP
J 0
(-3000 5100);
DISPLAY 1.021277 (-3000 5100);
PAINT ORANGE (-3000 5100);
DISPLAY INVISIBLE (-3000 5100);
FORCEPROP 2 LAST SEC 1
J 0
(-3000 5100);
DISPLAY 0.680851 (-3000 5100);
PAINT MONO (-3000 5100);
DISPLAY INVISIBLE (-3000 5100);
FORCEPROP 2 LAST CDS_LOCATION J1G3
J 0
(-3000 5050);
DISPLAY 0.617021 (-3000 5050);
PAINT AQUA (-3000 5050);
DISPLAY INVISIBLE (-3000 5050);
FORCEPROP 1 LAST PATH I186
J 0
(-2550 5000);
PAINT GREEN (-2550 5000);
DISPLAY INVISIBLE (-2550 5000);
FORCEPROP 2 LAST ROOM DDR4_CH_J
J 0
(-2550 3150);
PAINT ORANGE (-2550 3150);
DISPLAY INVISIBLE (-2550 3150);
FORCEADD P12V_NVDIMM_GHJ..1
(350 2975);
FORCEPROP 3 LASTPIN (350 2925) SIG_NAME P12V_NVDIMM_GHJ\g
J 0
(360 2935);
DISPLAY 0.659574 (360 2935);
PAINT MONO (360 2935);
DISPLAY INVISIBLE (360 2935);
FORCEPROP 1 LAST VOLTAGE 12.0
J 0
(305 2932);
DISPLAY 0.340426 (305 2932);
PAINT SKYBLUE (305 2932);
DISPLAY INVISIBLE (305 2932);
FORCEPROP 2 LAST CDS_LIB mstr_symbols
J 0
(350 2975);
PAINT ORANGE (350 2975);
DISPLAY INVISIBLE (350 2975);
FORCEPROP 1 LAST BODY_TYPE PLUMBING
J 0
(305 2932);
DISPLAY 0.340426 (305 2932);
PAINT GREEN (305 2932);
DISPLAY INVISIBLE (305 2932);
FORCEPROP 1 LAST PATH I187
J 0
(400 3000);
DISPLAY 0.872340 (400 3000);
PAINT AQUA (400 3000);
DISPLAY INVISIBLE (400 3000);
FORCEPROP 1 LAST HDL_POWER P12V_NVDIMM_GHJ
J 1
(350 3025);
DISPLAY 0.872340 (350 3025);
PAINT GREEN (350 3025);
DISPLAY INVISIBLE (350 3025);
FORCEADD OFFPAGE..3
(1550 5200);
FORCEPROP 2 LAST $XR0 59 
J 0
(1764 5200);
DISPLAY 0.638298 (1764 5200);
PAINT MONO (1764 5200);
FORCEPROP 2 LAST $XR1 82 
J 0
(1854 5200);
DISPLAY 0.638298 (1854 5200);
PAINT MONO (1854 5200);
FORCEPROP 2 LAST CDS_LIB mstr_standard
J 0
(1550 5200);
DISPLAY 0.787234 (1550 5200);
PAINT MONO (1550 5200);
DISPLAY INVISIBLE (1550 5200);
FORCEPROP 1 LAST OFFPAGE TRUE
J 0
(1875 5075);
DISPLAY 0.936170 (1875 5075);
PAINT GREEN (1875 5075);
DISPLAY INVISIBLE (1875 5075);
FORCEPROP 1 LAST COMMENT_BODY TRUE
J 0
(1500 5100);
DISPLAY 0.936170 (1500 5100);
PAINT GREEN (1500 5100);
DISPLAY INVISIBLE (1500 5100);
FORCEPROP 2 LAST PATH I2
J 0
(1750 5275);
DISPLAY 0.787234 (1750 5275);
PAINT MONO (1750 5275);
DISPLAY INVISIBLE (1750 5275);
FORCEADD TAP..6
R 2
(850 4300);
FORCEPROP 3 LASTPIN (800 4300) SIG_NAME M_J_DQS_DN<9>
J 0
(810 4310);
DISPLAY 0.659574 (810 4310);
PAINT MONO (810 4310);
DISPLAY INVISIBLE (810 4310);
FORCEPROP 1 LASTPIN (800 4300) BN 9
J 2
(850 4310);
DISPLAY 0.617021 (850 4310);
PAINT PINK (850 4310);
FORCEPROP 2 LAST CDS_LIB mstr_standard
J 0
(850 4300);
DISPLAY 0.787234 (850 4300);
PAINT MONO (850 4300);
DISPLAY INVISIBLE (850 4300);
FORCEPROP 1 LAST BODY_TYPE PLUMBING
J 2
(850 4250);
DISPLAY 1.234043 (850 4250);
PAINT GREEN (850 4250);
DISPLAY INVISIBLE (850 4250);
FORCEPROP 1 LAST HDL_TAP TRUE
J 2
(525 4175);
DISPLAY 1.234043 (525 4175);
PAINT GREEN (525 4175);
DISPLAY INVISIBLE (525 4175);
FORCEPROP 1 LAST PATH I20
J 2
(850 4300);
DISPLAY 0.936170 (850 4300);
PAINT GREEN (850 4300);
DISPLAY INVISIBLE (850 4300);
FORCEADD TAP..6
R 2
(850 4400);
FORCEPROP 3 LASTPIN (800 4400) SIG_NAME M_J_DQS_DN<10>
J 0
(810 4410);
DISPLAY 0.659574 (810 4410);
PAINT MONO (810 4410);
DISPLAY INVISIBLE (810 4410);
FORCEPROP 1 LASTPIN (800 4400) BN 10
J 2
(850 4410);
DISPLAY 0.617021 (850 4410);
PAINT PINK (850 4410);
FORCEPROP 2 LAST CDS_LIB mstr_standard
J 0
(850 4400);
DISPLAY 0.787234 (850 4400);
PAINT MONO (850 4400);
DISPLAY INVISIBLE (850 4400);
FORCEPROP 1 LAST BODY_TYPE PLUMBING
J 2
(850 4350);
DISPLAY 1.234043 (850 4350);
PAINT GREEN (850 4350);
DISPLAY INVISIBLE (850 4350);
FORCEPROP 1 LAST HDL_TAP TRUE
J 2
(525 4275);
DISPLAY 1.234043 (525 4275);
PAINT GREEN (525 4275);
DISPLAY INVISIBLE (525 4275);
FORCEPROP 1 LAST PATH I21
J 2
(850 4400);
DISPLAY 0.936170 (850 4400);
PAINT GREEN (850 4400);
DISPLAY INVISIBLE (850 4400);
FORCEADD TAP..6
R 2
(850 4200);
FORCEPROP 3 LASTPIN (800 4200) SIG_NAME M_J_DQS_DN<8>
J 0
(810 4210);
DISPLAY 0.659574 (810 4210);
PAINT MONO (810 4210);
DISPLAY INVISIBLE (810 4210);
FORCEPROP 1 LASTPIN (800 4200) BN 8
J 2
(850 4210);
DISPLAY 0.617021 (850 4210);
PAINT PINK (850 4210);
FORCEPROP 2 LAST CDS_LIB mstr_standard
J 0
(850 4200);
DISPLAY 0.787234 (850 4200);
PAINT MONO (850 4200);
DISPLAY INVISIBLE (850 4200);
FORCEPROP 1 LAST BODY_TYPE PLUMBING
J 2
(850 4150);
DISPLAY 1.234043 (850 4150);
PAINT GREEN (850 4150);
DISPLAY INVISIBLE (850 4150);
FORCEPROP 1 LAST HDL_TAP TRUE
J 2
(525 4075);
DISPLAY 1.234043 (525 4075);
PAINT GREEN (525 4075);
DISPLAY INVISIBLE (525 4075);
FORCEPROP 1 LAST PATH I22
J 2
(850 4200);
DISPLAY 0.936170 (850 4200);
PAINT GREEN (850 4200);
DISPLAY INVISIBLE (850 4200);
FORCEADD TAP..6
R 2
(850 4100);
FORCEPROP 3 LASTPIN (800 4100) SIG_NAME M_J_DQS_DN<7>
J 0
(810 4110);
DISPLAY 0.659574 (810 4110);
PAINT MONO (810 4110);
DISPLAY INVISIBLE (810 4110);
FORCEPROP 1 LASTPIN (800 4100) BN 7
J 2
(850 4110);
DISPLAY 0.617021 (850 4110);
PAINT PINK (850 4110);
FORCEPROP 2 LAST CDS_LIB mstr_standard
J 0
(850 4100);
DISPLAY 0.787234 (850 4100);
PAINT MONO (850 4100);
DISPLAY INVISIBLE (850 4100);
FORCEPROP 1 LAST BODY_TYPE PLUMBING
J 2
(850 4050);
DISPLAY 1.234043 (850 4050);
PAINT GREEN (850 4050);
DISPLAY INVISIBLE (850 4050);
FORCEPROP 1 LAST HDL_TAP TRUE
J 2
(525 3975);
DISPLAY 1.234043 (525 3975);
PAINT GREEN (525 3975);
DISPLAY INVISIBLE (525 3975);
FORCEPROP 1 LAST PATH I23
J 2
(850 4100);
DISPLAY 0.936170 (850 4100);
PAINT GREEN (850 4100);
DISPLAY INVISIBLE (850 4100);
FORCEADD TAP..6
R 2
(850 4000);
FORCEPROP 3 LASTPIN (800 4000) SIG_NAME M_J_DQS_DN<6>
J 0
(810 4010);
DISPLAY 0.659574 (810 4010);
PAINT MONO (810 4010);
DISPLAY INVISIBLE (810 4010);
FORCEPROP 1 LASTPIN (800 4000) BN 6
J 2
(850 4010);
DISPLAY 0.617021 (850 4010);
PAINT PINK (850 4010);
FORCEPROP 2 LAST CDS_LIB mstr_standard
J 0
(850 4000);
DISPLAY 0.787234 (850 4000);
PAINT MONO (850 4000);
DISPLAY INVISIBLE (850 4000);
FORCEPROP 1 LAST BODY_TYPE PLUMBING
J 2
(850 3950);
DISPLAY 1.234043 (850 3950);
PAINT GREEN (850 3950);
DISPLAY INVISIBLE (850 3950);
FORCEPROP 1 LAST HDL_TAP TRUE
J 2
(525 3875);
DISPLAY 1.234043 (525 3875);
PAINT GREEN (525 3875);
DISPLAY INVISIBLE (525 3875);
FORCEPROP 1 LAST PATH I24
J 2
(850 4000);
DISPLAY 0.936170 (850 4000);
PAINT GREEN (850 4000);
DISPLAY INVISIBLE (850 4000);
FORCEADD TAP..6
R 2
(650 4250);
FORCEPROP 3 LASTPIN (600 4250) SIG_NAME M_J_DQS_DP<8>
J 0
(610 4260);
DISPLAY 0.659574 (610 4260);
PAINT MONO (610 4260);
DISPLAY INVISIBLE (610 4260);
FORCEPROP 1 LASTPIN (600 4250) BN 8
J 2
(650 4260);
DISPLAY 0.617021 (650 4260);
PAINT PINK (650 4260);
FORCEPROP 2 LAST CDS_LIB mstr_standard
J 0
(650 4250);
DISPLAY 0.787234 (650 4250);
PAINT MONO (650 4250);
DISPLAY INVISIBLE (650 4250);
FORCEPROP 1 LAST BODY_TYPE PLUMBING
J 2
(650 4200);
DISPLAY 1.234043 (650 4200);
PAINT GREEN (650 4200);
DISPLAY INVISIBLE (650 4200);
FORCEPROP 1 LAST HDL_TAP TRUE
J 2
(325 4125);
DISPLAY 1.234043 (325 4125);
PAINT GREEN (325 4125);
DISPLAY INVISIBLE (325 4125);
FORCEPROP 1 LAST PATH I25
J 2
(650 4250);
DISPLAY 0.936170 (650 4250);
PAINT GREEN (650 4250);
DISPLAY INVISIBLE (650 4250);
FORCEADD TAP..6
R 2
(650 4350);
FORCEPROP 3 LASTPIN (600 4350) SIG_NAME M_J_DQS_DP<9>
J 0
(610 4360);
DISPLAY 0.659574 (610 4360);
PAINT MONO (610 4360);
DISPLAY INVISIBLE (610 4360);
FORCEPROP 1 LASTPIN (600 4350) BN 9
J 2
(650 4360);
DISPLAY 0.617021 (650 4360);
PAINT PINK (650 4360);
FORCEPROP 2 LAST CDS_LIB mstr_standard
J 0
(650 4350);
DISPLAY 0.787234 (650 4350);
PAINT MONO (650 4350);
DISPLAY INVISIBLE (650 4350);
FORCEPROP 1 LAST BODY_TYPE PLUMBING
J 2
(650 4300);
DISPLAY 1.234043 (650 4300);
PAINT GREEN (650 4300);
DISPLAY INVISIBLE (650 4300);
FORCEPROP 1 LAST HDL_TAP TRUE
J 2
(325 4225);
DISPLAY 1.234043 (325 4225);
PAINT GREEN (325 4225);
DISPLAY INVISIBLE (325 4225);
FORCEPROP 1 LAST PATH I26
J 2
(650 4350);
DISPLAY 0.936170 (650 4350);
PAINT GREEN (650 4350);
DISPLAY INVISIBLE (650 4350);
FORCEADD TAP..6
R 2
(650 4450);
FORCEPROP 3 LASTPIN (600 4450) SIG_NAME M_J_DQS_DP<10>
J 0
(610 4460);
DISPLAY 0.659574 (610 4460);
PAINT MONO (610 4460);
DISPLAY INVISIBLE (610 4460);
FORCEPROP 1 LASTPIN (600 4450) BN 10
J 2
(650 4460);
DISPLAY 0.617021 (650 4460);
PAINT PINK (650 4460);
FORCEPROP 2 LAST CDS_LIB mstr_standard
J 0
(650 4450);
DISPLAY 0.787234 (650 4450);
PAINT MONO (650 4450);
DISPLAY INVISIBLE (650 4450);
FORCEPROP 1 LAST BODY_TYPE PLUMBING
J 2
(650 4400);
DISPLAY 1.234043 (650 4400);
PAINT GREEN (650 4400);
DISPLAY INVISIBLE (650 4400);
FORCEPROP 1 LAST HDL_TAP TRUE
J 2
(325 4325);
DISPLAY 1.234043 (325 4325);
PAINT GREEN (325 4325);
DISPLAY INVISIBLE (325 4325);
FORCEPROP 1 LAST PATH I27
J 2
(650 4450);
DISPLAY 0.936170 (650 4450);
PAINT GREEN (650 4450);
DISPLAY INVISIBLE (650 4450);
FORCEADD TAP..6
R 2
(650 4150);
FORCEPROP 3 LASTPIN (600 4150) SIG_NAME M_J_DQS_DP<7>
J 0
(610 4160);
DISPLAY 0.659574 (610 4160);
PAINT MONO (610 4160);
DISPLAY INVISIBLE (610 4160);
FORCEPROP 1 LASTPIN (600 4150) BN 7
J 2
(650 4160);
DISPLAY 0.617021 (650 4160);
PAINT PINK (650 4160);
FORCEPROP 2 LAST CDS_LIB mstr_standard
J 0
(650 4150);
DISPLAY 0.787234 (650 4150);
PAINT MONO (650 4150);
DISPLAY INVISIBLE (650 4150);
FORCEPROP 1 LAST BODY_TYPE PLUMBING
J 2
(650 4100);
DISPLAY 1.234043 (650 4100);
PAINT GREEN (650 4100);
DISPLAY INVISIBLE (650 4100);
FORCEPROP 1 LAST HDL_TAP TRUE
J 2
(325 4025);
DISPLAY 1.234043 (325 4025);
PAINT GREEN (325 4025);
DISPLAY INVISIBLE (325 4025);
FORCEPROP 1 LAST PATH I28
J 2
(650 4150);
DISPLAY 0.936170 (650 4150);
PAINT GREEN (650 4150);
DISPLAY INVISIBLE (650 4150);
FORCEADD TAP..6
R 2
(650 4050);
FORCEPROP 3 LASTPIN (600 4050) SIG_NAME M_J_DQS_DP<6>
J 0
(610 4060);
DISPLAY 0.659574 (610 4060);
PAINT MONO (610 4060);
DISPLAY INVISIBLE (610 4060);
FORCEPROP 1 LASTPIN (600 4050) BN 6
J 2
(650 4060);
DISPLAY 0.617021 (650 4060);
PAINT PINK (650 4060);
FORCEPROP 2 LAST CDS_LIB mstr_standard
J 0
(650 4050);
DISPLAY 0.787234 (650 4050);
PAINT MONO (650 4050);
DISPLAY INVISIBLE (650 4050);
FORCEPROP 1 LAST BODY_TYPE PLUMBING
J 2
(650 4000);
DISPLAY 1.234043 (650 4000);
PAINT GREEN (650 4000);
DISPLAY INVISIBLE (650 4000);
FORCEPROP 1 LAST HDL_TAP TRUE
J 2
(325 3925);
DISPLAY 1.234043 (325 3925);
PAINT GREEN (325 3925);
DISPLAY INVISIBLE (325 3925);
FORCEPROP 1 LAST PATH I29
J 2
(650 4050);
DISPLAY 0.936170 (650 4050);
PAINT GREEN (650 4050);
DISPLAY INVISIBLE (650 4050);
FORCEADD TAP..6
R 2
(850 5100);
FORCEPROP 3 LASTPIN (800 5100) SIG_NAME M_J_DQS_DN<17>
J 0
(810 5110);
DISPLAY 0.659574 (810 5110);
PAINT MONO (810 5110);
DISPLAY INVISIBLE (810 5110);
FORCEPROP 1 LASTPIN (800 5100) BN 17
J 2
(850 5110);
DISPLAY 0.617021 (850 5110);
PAINT PINK (850 5110);
FORCEPROP 2 LAST CDS_LIB mstr_standard
J 2
(850 5100);
DISPLAY 0.787234 (850 5100);
PAINT MONO (850 5100);
DISPLAY INVISIBLE (850 5100);
FORCEPROP 1 LAST BODY_TYPE PLUMBING
J 2
(850 5050);
DISPLAY 1.234043 (850 5050);
PAINT GREEN (850 5050);
DISPLAY INVISIBLE (850 5050);
FORCEPROP 1 LAST HDL_TAP TRUE
J 2
(525 4975);
DISPLAY 1.234043 (525 4975);
PAINT GREEN (525 4975);
DISPLAY INVISIBLE (525 4975);
FORCEPROP 1 LAST PATH I3
J 2
(850 5100);
DISPLAY 0.936170 (850 5100);
PAINT GREEN (850 5100);
DISPLAY INVISIBLE (850 5100);
FORCEADD TAP..6
R 2
(850 3900);
FORCEPROP 3 LASTPIN (800 3900) SIG_NAME M_J_DQS_DN<5>
J 0
(810 3910);
DISPLAY 0.659574 (810 3910);
PAINT MONO (810 3910);
DISPLAY INVISIBLE (810 3910);
FORCEPROP 1 LASTPIN (800 3900) BN 5
J 2
(850 3910);
DISPLAY 0.617021 (850 3910);
PAINT PINK (850 3910);
FORCEPROP 2 LAST CDS_LIB mstr_standard
J 0
(850 3900);
DISPLAY 0.787234 (850 3900);
PAINT MONO (850 3900);
DISPLAY INVISIBLE (850 3900);
FORCEPROP 1 LAST BODY_TYPE PLUMBING
J 2
(850 3850);
DISPLAY 1.234043 (850 3850);
PAINT GREEN (850 3850);
DISPLAY INVISIBLE (850 3850);
FORCEPROP 1 LAST HDL_TAP TRUE
J 2
(525 3775);
DISPLAY 1.234043 (525 3775);
PAINT GREEN (525 3775);
DISPLAY INVISIBLE (525 3775);
FORCEPROP 1 LAST PATH I30
J 2
(850 3900);
DISPLAY 0.936170 (850 3900);
PAINT GREEN (850 3900);
DISPLAY INVISIBLE (850 3900);
FORCEADD TAP..6
R 2
(850 3800);
FORCEPROP 3 LASTPIN (800 3800) SIG_NAME M_J_DQS_DN<4>
J 0
(810 3810);
DISPLAY 0.659574 (810 3810);
PAINT MONO (810 3810);
DISPLAY INVISIBLE (810 3810);
FORCEPROP 1 LASTPIN (800 3800) BN 4
J 2
(850 3810);
DISPLAY 0.617021 (850 3810);
PAINT PINK (850 3810);
FORCEPROP 2 LAST CDS_LIB mstr_standard
J 0
(850 3800);
DISPLAY 0.787234 (850 3800);
PAINT MONO (850 3800);
DISPLAY INVISIBLE (850 3800);
FORCEPROP 1 LAST BODY_TYPE PLUMBING
J 2
(850 3750);
DISPLAY 1.234043 (850 3750);
PAINT GREEN (850 3750);
DISPLAY INVISIBLE (850 3750);
FORCEPROP 1 LAST HDL_TAP TRUE
J 2
(525 3675);
DISPLAY 1.234043 (525 3675);
PAINT GREEN (525 3675);
DISPLAY INVISIBLE (525 3675);
FORCEPROP 1 LAST PATH I31
J 2
(850 3800);
DISPLAY 0.936170 (850 3800);
PAINT GREEN (850 3800);
DISPLAY INVISIBLE (850 3800);
FORCEADD TAP..6
R 2
(850 3700);
FORCEPROP 3 LASTPIN (800 3700) SIG_NAME M_J_DQS_DN<3>
J 0
(810 3710);
DISPLAY 0.659574 (810 3710);
PAINT MONO (810 3710);
DISPLAY INVISIBLE (810 3710);
FORCEPROP 1 LASTPIN (800 3700) BN 3
J 2
(850 3710);
DISPLAY 0.617021 (850 3710);
PAINT PINK (850 3710);
FORCEPROP 2 LAST CDS_LIB mstr_standard
J 0
(850 3700);
DISPLAY 0.787234 (850 3700);
PAINT MONO (850 3700);
DISPLAY INVISIBLE (850 3700);
FORCEPROP 1 LAST BODY_TYPE PLUMBING
J 2
(850 3650);
DISPLAY 1.234043 (850 3650);
PAINT GREEN (850 3650);
DISPLAY INVISIBLE (850 3650);
FORCEPROP 1 LAST HDL_TAP TRUE
J 2
(525 3575);
DISPLAY 1.234043 (525 3575);
PAINT GREEN (525 3575);
DISPLAY INVISIBLE (525 3575);
FORCEPROP 1 LAST PATH I32
J 2
(850 3700);
DISPLAY 0.936170 (850 3700);
PAINT GREEN (850 3700);
DISPLAY INVISIBLE (850 3700);
FORCEADD TAP..6
R 2
(850 3600);
FORCEPROP 3 LASTPIN (800 3600) SIG_NAME M_J_DQS_DN<2>
J 0
(810 3610);
DISPLAY 0.659574 (810 3610);
PAINT MONO (810 3610);
DISPLAY INVISIBLE (810 3610);
FORCEPROP 1 LASTPIN (800 3600) BN 2
J 2
(850 3610);
DISPLAY 0.617021 (850 3610);
PAINT PINK (850 3610);
FORCEPROP 2 LAST CDS_LIB mstr_standard
J 0
(850 3600);
DISPLAY 0.787234 (850 3600);
PAINT MONO (850 3600);
DISPLAY INVISIBLE (850 3600);
FORCEPROP 1 LAST BODY_TYPE PLUMBING
J 2
(850 3550);
DISPLAY 1.234043 (850 3550);
PAINT GREEN (850 3550);
DISPLAY INVISIBLE (850 3550);
FORCEPROP 1 LAST HDL_TAP TRUE
J 2
(525 3475);
DISPLAY 1.234043 (525 3475);
PAINT GREEN (525 3475);
DISPLAY INVISIBLE (525 3475);
FORCEPROP 1 LAST PATH I33
J 2
(850 3600);
DISPLAY 0.936170 (850 3600);
PAINT GREEN (850 3600);
DISPLAY INVISIBLE (850 3600);
FORCEADD TAP..6
R 2
(850 3500);
FORCEPROP 3 LASTPIN (800 3500) SIG_NAME M_J_DQS_DN<1>
J 0
(810 3510);
DISPLAY 0.659574 (810 3510);
PAINT MONO (810 3510);
DISPLAY INVISIBLE (810 3510);
FORCEPROP 1 LASTPIN (800 3500) BN 1
J 2
(850 3510);
DISPLAY 0.617021 (850 3510);
PAINT PINK (850 3510);
FORCEPROP 2 LAST CDS_LIB mstr_standard
J 0
(850 3500);
DISPLAY 0.787234 (850 3500);
PAINT MONO (850 3500);
DISPLAY INVISIBLE (850 3500);
FORCEPROP 1 LAST BODY_TYPE PLUMBING
J 2
(850 3450);
DISPLAY 1.234043 (850 3450);
PAINT GREEN (850 3450);
DISPLAY INVISIBLE (850 3450);
FORCEPROP 1 LAST HDL_TAP TRUE
J 2
(525 3375);
DISPLAY 1.234043 (525 3375);
PAINT GREEN (525 3375);
DISPLAY INVISIBLE (525 3375);
FORCEPROP 1 LAST PATH I34
J 2
(850 3500);
DISPLAY 0.936170 (850 3500);
PAINT GREEN (850 3500);
DISPLAY INVISIBLE (850 3500);
FORCEADD TAP..6
R 2
(650 3750);
FORCEPROP 3 LASTPIN (600 3750) SIG_NAME M_J_DQS_DP<3>
J 0
(610 3760);
DISPLAY 0.659574 (610 3760);
PAINT MONO (610 3760);
DISPLAY INVISIBLE (610 3760);
FORCEPROP 1 LASTPIN (600 3750) BN 3
J 2
(650 3760);
DISPLAY 0.617021 (650 3760);
PAINT PINK (650 3760);
FORCEPROP 2 LAST CDS_LIB mstr_standard
J 0
(650 3750);
DISPLAY 0.787234 (650 3750);
PAINT MONO (650 3750);
DISPLAY INVISIBLE (650 3750);
FORCEPROP 1 LAST BODY_TYPE PLUMBING
J 2
(650 3700);
DISPLAY 1.234043 (650 3700);
PAINT GREEN (650 3700);
DISPLAY INVISIBLE (650 3700);
FORCEPROP 1 LAST HDL_TAP TRUE
J 2
(325 3625);
DISPLAY 1.234043 (325 3625);
PAINT GREEN (325 3625);
DISPLAY INVISIBLE (325 3625);
FORCEPROP 1 LAST PATH I35
J 2
(650 3750);
DISPLAY 0.936170 (650 3750);
PAINT GREEN (650 3750);
DISPLAY INVISIBLE (650 3750);
FORCEADD TAP..6
R 2
(650 3850);
FORCEPROP 3 LASTPIN (600 3850) SIG_NAME M_J_DQS_DP<4>
J 0
(610 3860);
DISPLAY 0.659574 (610 3860);
PAINT MONO (610 3860);
DISPLAY INVISIBLE (610 3860);
FORCEPROP 1 LASTPIN (600 3850) BN 4
J 2
(650 3860);
DISPLAY 0.617021 (650 3860);
PAINT PINK (650 3860);
FORCEPROP 2 LAST CDS_LIB mstr_standard
J 0
(650 3850);
DISPLAY 0.787234 (650 3850);
PAINT MONO (650 3850);
DISPLAY INVISIBLE (650 3850);
FORCEPROP 1 LAST BODY_TYPE PLUMBING
J 2
(650 3800);
DISPLAY 1.234043 (650 3800);
PAINT GREEN (650 3800);
DISPLAY INVISIBLE (650 3800);
FORCEPROP 1 LAST HDL_TAP TRUE
J 2
(325 3725);
DISPLAY 1.234043 (325 3725);
PAINT GREEN (325 3725);
DISPLAY INVISIBLE (325 3725);
FORCEPROP 1 LAST PATH I36
J 2
(650 3850);
DISPLAY 0.936170 (650 3850);
PAINT GREEN (650 3850);
DISPLAY INVISIBLE (650 3850);
FORCEADD TAP..6
R 2
(650 3950);
FORCEPROP 3 LASTPIN (600 3950) SIG_NAME M_J_DQS_DP<5>
J 0
(610 3960);
DISPLAY 0.659574 (610 3960);
PAINT MONO (610 3960);
DISPLAY INVISIBLE (610 3960);
FORCEPROP 1 LASTPIN (600 3950) BN 5
J 2
(650 3960);
DISPLAY 0.617021 (650 3960);
PAINT PINK (650 3960);
FORCEPROP 2 LAST CDS_LIB mstr_standard
J 0
(650 3950);
DISPLAY 0.787234 (650 3950);
PAINT MONO (650 3950);
DISPLAY INVISIBLE (650 3950);
FORCEPROP 1 LAST BODY_TYPE PLUMBING
J 2
(650 3900);
DISPLAY 1.234043 (650 3900);
PAINT GREEN (650 3900);
DISPLAY INVISIBLE (650 3900);
FORCEPROP 1 LAST HDL_TAP TRUE
J 2
(325 3825);
DISPLAY 1.234043 (325 3825);
PAINT GREEN (325 3825);
DISPLAY INVISIBLE (325 3825);
FORCEPROP 1 LAST PATH I37
J 2
(650 3950);
DISPLAY 0.936170 (650 3950);
PAINT GREEN (650 3950);
DISPLAY INVISIBLE (650 3950);
FORCEADD TAP..6
R 2
(650 3550);
FORCEPROP 3 LASTPIN (600 3550) SIG_NAME M_J_DQS_DP<1>
J 0
(610 3560);
DISPLAY 0.659574 (610 3560);
PAINT MONO (610 3560);
DISPLAY INVISIBLE (610 3560);
FORCEPROP 1 LASTPIN (600 3550) BN 1
J 2
(650 3560);
DISPLAY 0.617021 (650 3560);
PAINT PINK (650 3560);
FORCEPROP 2 LAST CDS_LIB mstr_standard
J 0
(650 3550);
DISPLAY 0.787234 (650 3550);
PAINT MONO (650 3550);
DISPLAY INVISIBLE (650 3550);
FORCEPROP 1 LAST BODY_TYPE PLUMBING
J 2
(650 3500);
DISPLAY 1.234043 (650 3500);
PAINT GREEN (650 3500);
DISPLAY INVISIBLE (650 3500);
FORCEPROP 1 LAST HDL_TAP TRUE
J 2
(325 3425);
DISPLAY 1.234043 (325 3425);
PAINT GREEN (325 3425);
DISPLAY INVISIBLE (325 3425);
FORCEPROP 1 LAST PATH I38
J 2
(650 3550);
DISPLAY 0.936170 (650 3550);
PAINT GREEN (650 3550);
DISPLAY INVISIBLE (650 3550);
FORCEADD TAP..6
R 2
(650 3450);
FORCEPROP 3 LASTPIN (600 3450) SIG_NAME M_J_DQS_DP<0>
J 0
(610 3460);
DISPLAY 0.659574 (610 3460);
PAINT MONO (610 3460);
DISPLAY INVISIBLE (610 3460);
FORCEPROP 1 LASTPIN (600 3450) BN 0
J 2
(650 3460);
DISPLAY 0.617021 (650 3460);
PAINT PINK (650 3460);
FORCEPROP 2 LAST CDS_LIB mstr_standard
J 0
(650 3450);
DISPLAY 0.787234 (650 3450);
PAINT MONO (650 3450);
DISPLAY INVISIBLE (650 3450);
FORCEPROP 1 LAST BODY_TYPE PLUMBING
J 2
(650 3400);
DISPLAY 1.234043 (650 3400);
PAINT GREEN (650 3400);
DISPLAY INVISIBLE (650 3400);
FORCEPROP 1 LAST HDL_TAP TRUE
J 2
(325 3325);
DISPLAY 1.234043 (325 3325);
PAINT GREEN (325 3325);
DISPLAY INVISIBLE (325 3325);
FORCEPROP 1 LAST PATH I39
J 2
(650 3450);
DISPLAY 0.936170 (650 3450);
PAINT GREEN (650 3450);
DISPLAY INVISIBLE (650 3450);
FORCEADD TAP..6
R 2
(850 5000);
FORCEPROP 3 LASTPIN (800 5000) SIG_NAME M_J_DQS_DN<16>
J 0
(810 5010);
DISPLAY 0.659574 (810 5010);
PAINT MONO (810 5010);
DISPLAY INVISIBLE (810 5010);
FORCEPROP 1 LASTPIN (800 5000) BN 16
J 2
(850 5010);
DISPLAY 0.617021 (850 5010);
PAINT PINK (850 5010);
FORCEPROP 2 LAST CDS_LIB mstr_standard
J 0
(850 5000);
DISPLAY 0.787234 (850 5000);
PAINT MONO (850 5000);
DISPLAY INVISIBLE (850 5000);
FORCEPROP 1 LAST BODY_TYPE PLUMBING
J 2
(850 4950);
DISPLAY 1.234043 (850 4950);
PAINT GREEN (850 4950);
DISPLAY INVISIBLE (850 4950);
FORCEPROP 1 LAST HDL_TAP TRUE
J 2
(525 4875);
DISPLAY 1.234043 (525 4875);
PAINT GREEN (525 4875);
DISPLAY INVISIBLE (525 4875);
FORCEPROP 1 LAST PATH I4
J 2
(850 5000);
DISPLAY 0.936170 (850 5000);
PAINT GREEN (850 5000);
DISPLAY INVISIBLE (850 5000);
FORCEADD TAP..6
R 2
(650 3650);
FORCEPROP 3 LASTPIN (600 3650) SIG_NAME M_J_DQS_DP<2>
J 0
(610 3660);
DISPLAY 0.659574 (610 3660);
PAINT MONO (610 3660);
DISPLAY INVISIBLE (610 3660);
FORCEPROP 1 LASTPIN (600 3650) BN 2
J 2
(650 3660);
DISPLAY 0.617021 (650 3660);
PAINT PINK (650 3660);
FORCEPROP 2 LAST CDS_LIB mstr_standard
J 0
(650 3650);
DISPLAY 0.787234 (650 3650);
PAINT MONO (650 3650);
DISPLAY INVISIBLE (650 3650);
FORCEPROP 1 LAST BODY_TYPE PLUMBING
J 2
(650 3600);
DISPLAY 1.234043 (650 3600);
PAINT GREEN (650 3600);
DISPLAY INVISIBLE (650 3600);
FORCEPROP 1 LAST HDL_TAP TRUE
J 2
(325 3525);
DISPLAY 1.234043 (325 3525);
PAINT GREEN (325 3525);
DISPLAY INVISIBLE (325 3525);
FORCEPROP 1 LAST PATH I40
J 2
(650 3650);
DISPLAY 0.936170 (650 3650);
PAINT GREEN (650 3650);
DISPLAY INVISIBLE (650 3650);
FORCEADD TAP..6
R 2
(850 3400);
FORCEPROP 3 LASTPIN (800 3400) SIG_NAME M_J_DQS_DN<0>
J 0
(810 3410);
DISPLAY 0.659574 (810 3410);
PAINT MONO (810 3410);
DISPLAY INVISIBLE (810 3410);
FORCEPROP 1 LASTPIN (800 3400) BN 0
J 2
(850 3410);
DISPLAY 0.617021 (850 3410);
PAINT PINK (850 3410);
FORCEPROP 2 LAST CDS_LIB mstr_standard
J 0
(850 3400);
DISPLAY 0.787234 (850 3400);
PAINT MONO (850 3400);
DISPLAY INVISIBLE (850 3400);
FORCEPROP 1 LAST BODY_TYPE PLUMBING
J 2
(850 3350);
DISPLAY 1.234043 (850 3350);
PAINT GREEN (850 3350);
DISPLAY INVISIBLE (850 3350);
FORCEPROP 1 LAST HDL_TAP TRUE
J 2
(525 3275);
DISPLAY 1.234043 (525 3275);
PAINT GREEN (525 3275);
DISPLAY INVISIBLE (525 3275);
FORCEPROP 1 LAST PATH I41
J 2
(850 3400);
DISPLAY 0.936170 (850 3400);
PAINT GREEN (850 3400);
DISPLAY INVISIBLE (850 3400);
FORCEADD GND..1
R 2
(1050 1100);
FORCEPROP 3 LASTPIN (1050 1150) SIG_NAME GND\g
J 0
(1060 1160);
DISPLAY 0.659574 (1060 1160);
PAINT MONO (1060 1160);
DISPLAY INVISIBLE (1060 1160);
FORCEPROP 1 LAST VOLTAGE 0
J 0
(1050 1100);
PAINT SKYBLUE (1050 1100);
DISPLAY INVISIBLE (1050 1100);
FORCEPROP 2 LAST BOM_COST MEM
J 0
(1050 1105);
PAINT ORANGE (1050 1105);
DISPLAY INVISIBLE (1050 1105);
FORCEPROP 2 LAST CDS_LIB mstr_symbols
J 0
(1050 1100);
DISPLAY 0.787234 (1050 1100);
PAINT MONO (1050 1100);
DISPLAY INVISIBLE (1050 1100);
FORCEPROP 1 LAST SIZE 1B
J 2
(975 1050);
DISPLAY 1.170213 (975 1050);
PAINT GREEN (975 1050);
DISPLAY INVISIBLE (975 1050);
FORCEPROP 1 LAST BODY_TYPE PLUMBING
J 2
(1095 1057);
DISPLAY 0.340426 (1095 1057);
PAINT GREEN (1095 1057);
DISPLAY INVISIBLE (1095 1057);
FORCEPROP 1 LAST PATH I44
J 2
(975 1100);
DISPLAY 0.936170 (975 1100);
PAINT GREEN (975 1100);
DISPLAY INVISIBLE (975 1100);
FORCEPROP 2 LAST ROOM DDR4_CH_J
J 0
(1050 1105);
PAINT ORANGE (1050 1105);
DISPLAY INVISIBLE (1050 1105);
FORCEPROP 1 LAST HDL_POWER GND
J 2
(1050 1250);
DISPLAY 0.553191 (1050 1250);
PAINT GREEN (1050 1250);
DISPLAY INVISIBLE (1050 1250);
FORCEADD OFFPAGE..3
(-1300 4850);
FORCEPROP 2 LAST $XR0 59 
J 0
(-1086 4850);
DISPLAY 0.638298 (-1086 4850);
PAINT MONO (-1086 4850);
FORCEPROP 2 LAST $XR1 82 
J 0
(-996 4850);
DISPLAY 0.638298 (-996 4850);
PAINT MONO (-996 4850);
FORCEPROP 2 LAST CDS_LIB mstr_standard
J 0
(-1300 4850);
DISPLAY 0.787234 (-1300 4850);
PAINT MONO (-1300 4850);
DISPLAY INVISIBLE (-1300 4850);
FORCEPROP 1 LAST OFFPAGE TRUE
J 0
(-975 4725);
DISPLAY 0.936170 (-975 4725);
PAINT GREEN (-975 4725);
DISPLAY INVISIBLE (-975 4725);
FORCEPROP 1 LAST COMMENT_BODY TRUE
J 0
(-1350 4750);
DISPLAY 0.936170 (-1350 4750);
PAINT GREEN (-1350 4750);
DISPLAY INVISIBLE (-1350 4750);
FORCEPROP 2 LAST PATH I45
J 0
(-1100 4925);
DISPLAY 0.787234 (-1100 4925);
PAINT MONO (-1100 4925);
DISPLAY INVISIBLE (-1100 4925);
FORCEADD TAP..6
R 2
(-1800 4800);
FORCEPROP 3 LASTPIN (-1850 4800) SIG_NAME M_J_DQ<62>
J 0
(-1840 4810);
DISPLAY 0.659574 (-1840 4810);
PAINT MONO (-1840 4810);
DISPLAY INVISIBLE (-1840 4810);
FORCEPROP 1 LASTPIN (-1850 4800) BN 62
J 2
(-1800 4810);
DISPLAY 0.617021 (-1800 4810);
PAINT PINK (-1800 4810);
FORCEPROP 2 LAST CDS_LIB mstr_standard
J 2
(-1800 4800);
DISPLAY 0.787234 (-1800 4800);
PAINT MONO (-1800 4800);
DISPLAY INVISIBLE (-1800 4800);
FORCEPROP 1 LAST BODY_TYPE PLUMBING
J 2
(-1800 4750);
DISPLAY 1.234043 (-1800 4750);
PAINT GREEN (-1800 4750);
DISPLAY INVISIBLE (-1800 4750);
FORCEPROP 1 LAST HDL_TAP TRUE
J 2
(-2125 4675);
DISPLAY 1.234043 (-2125 4675);
PAINT GREEN (-2125 4675);
DISPLAY INVISIBLE (-2125 4675);
FORCEPROP 1 LAST PATH I46
J 2
(-1800 4800);
DISPLAY 0.936170 (-1800 4800);
PAINT GREEN (-1800 4800);
DISPLAY INVISIBLE (-1800 4800);
FORCEADD TAP..6
R 2
(-1800 4550);
FORCEPROP 3 LASTPIN (-1850 4550) SIG_NAME M_J_DQ<59>
J 0
(-1840 4560);
DISPLAY 0.659574 (-1840 4560);
PAINT MONO (-1840 4560);
DISPLAY INVISIBLE (-1840 4560);
FORCEPROP 1 LASTPIN (-1850 4550) BN 59
J 2
(-1800 4560);
DISPLAY 0.617021 (-1800 4560);
PAINT PINK (-1800 4560);
FORCEPROP 2 LAST CDS_LIB mstr_standard
J 2
(-1800 4550);
DISPLAY 0.787234 (-1800 4550);
PAINT MONO (-1800 4550);
DISPLAY INVISIBLE (-1800 4550);
FORCEPROP 1 LAST BODY_TYPE PLUMBING
J 2
(-1800 4500);
DISPLAY 1.234043 (-1800 4500);
PAINT GREEN (-1800 4500);
DISPLAY INVISIBLE (-1800 4500);
FORCEPROP 1 LAST HDL_TAP TRUE
J 2
(-2125 4425);
DISPLAY 1.234043 (-2125 4425);
PAINT GREEN (-2125 4425);
DISPLAY INVISIBLE (-2125 4425);
FORCEPROP 1 LAST PATH I47
J 2
(-1800 4550);
DISPLAY 0.936170 (-1800 4550);
PAINT GREEN (-1800 4550);
DISPLAY INVISIBLE (-1800 4550);
FORCEADD TAP..6
R 2
(-1800 4600);
FORCEPROP 3 LASTPIN (-1850 4600) SIG_NAME M_J_DQ<58>
J 0
(-1840 4610);
DISPLAY 0.659574 (-1840 4610);
PAINT MONO (-1840 4610);
DISPLAY INVISIBLE (-1840 4610);
FORCEPROP 1 LASTPIN (-1850 4600) BN 58
J 2
(-1800 4610);
DISPLAY 0.617021 (-1800 4610);
PAINT PINK (-1800 4610);
FORCEPROP 2 LAST CDS_LIB mstr_standard
J 2
(-1800 4600);
DISPLAY 0.787234 (-1800 4600);
PAINT MONO (-1800 4600);
DISPLAY INVISIBLE (-1800 4600);
FORCEPROP 1 LAST BODY_TYPE PLUMBING
J 2
(-1800 4550);
DISPLAY 1.234043 (-1800 4550);
PAINT GREEN (-1800 4550);
DISPLAY INVISIBLE (-1800 4550);
FORCEPROP 1 LAST HDL_TAP TRUE
J 2
(-2125 4475);
DISPLAY 1.234043 (-2125 4475);
PAINT GREEN (-2125 4475);
DISPLAY INVISIBLE (-2125 4475);
FORCEPROP 1 LAST PATH I48
J 2
(-1800 4600);
DISPLAY 0.936170 (-1800 4600);
PAINT GREEN (-1800 4600);
DISPLAY INVISIBLE (-1800 4600);
FORCEADD TAP..6
R 2
(-1800 4700);
FORCEPROP 3 LASTPIN (-1850 4700) SIG_NAME M_J_DQ<60>
J 0
(-1840 4710);
DISPLAY 0.659574 (-1840 4710);
PAINT MONO (-1840 4710);
DISPLAY INVISIBLE (-1840 4710);
FORCEPROP 1 LASTPIN (-1850 4700) BN 60
J 2
(-1800 4710);
DISPLAY 0.617021 (-1800 4710);
PAINT PINK (-1800 4710);
FORCEPROP 2 LAST CDS_LIB mstr_standard
J 2
(-1800 4700);
DISPLAY 0.787234 (-1800 4700);
PAINT MONO (-1800 4700);
DISPLAY INVISIBLE (-1800 4700);
FORCEPROP 1 LAST BODY_TYPE PLUMBING
J 2
(-1800 4650);
DISPLAY 1.234043 (-1800 4650);
PAINT GREEN (-1800 4650);
DISPLAY INVISIBLE (-1800 4650);
FORCEPROP 1 LAST HDL_TAP TRUE
J 2
(-2125 4575);
DISPLAY 1.234043 (-2125 4575);
PAINT GREEN (-2125 4575);
DISPLAY INVISIBLE (-2125 4575);
FORCEPROP 1 LAST PATH I49
J 2
(-1800 4700);
DISPLAY 0.936170 (-1800 4700);
PAINT GREEN (-1800 4700);
DISPLAY INVISIBLE (-1800 4700);
FORCEADD TAP..6
R 2
(650 5150);
FORCEPROP 3 LASTPIN (600 5150) SIG_NAME M_J_DQS_DP<17>
J 0
(610 5160);
DISPLAY 0.659574 (610 5160);
PAINT MONO (610 5160);
DISPLAY INVISIBLE (610 5160);
FORCEPROP 1 LASTPIN (600 5150) BN 17
J 2
(650 5160);
DISPLAY 0.617021 (650 5160);
PAINT PINK (650 5160);
FORCEPROP 2 LAST CDS_LIB mstr_standard
J 2
(650 5150);
DISPLAY 0.787234 (650 5150);
PAINT MONO (650 5150);
DISPLAY INVISIBLE (650 5150);
FORCEPROP 1 LAST BODY_TYPE PLUMBING
J 2
(650 5100);
DISPLAY 1.234043 (650 5100);
PAINT GREEN (650 5100);
DISPLAY INVISIBLE (650 5100);
FORCEPROP 1 LAST HDL_TAP TRUE
J 2
(325 5025);
DISPLAY 1.234043 (325 5025);
PAINT GREEN (325 5025);
DISPLAY INVISIBLE (325 5025);
FORCEPROP 1 LAST PATH I5
J 2
(650 5150);
DISPLAY 0.936170 (650 5150);
PAINT GREEN (650 5150);
DISPLAY INVISIBLE (650 5150);
FORCEADD TAP..6
R 2
(-1800 4650);
FORCEPROP 3 LASTPIN (-1850 4650) SIG_NAME M_J_DQ<61>
J 0
(-1840 4660);
DISPLAY 0.659574 (-1840 4660);
PAINT MONO (-1840 4660);
DISPLAY INVISIBLE (-1840 4660);
FORCEPROP 1 LASTPIN (-1850 4650) BN 61
J 2
(-1800 4660);
DISPLAY 0.617021 (-1800 4660);
PAINT PINK (-1800 4660);
FORCEPROP 2 LAST CDS_LIB mstr_standard
J 2
(-1800 4650);
DISPLAY 0.787234 (-1800 4650);
PAINT MONO (-1800 4650);
DISPLAY INVISIBLE (-1800 4650);
FORCEPROP 1 LAST BODY_TYPE PLUMBING
J 2
(-1800 4600);
DISPLAY 1.234043 (-1800 4600);
PAINT GREEN (-1800 4600);
DISPLAY INVISIBLE (-1800 4600);
FORCEPROP 1 LAST HDL_TAP TRUE
J 2
(-2125 4525);
DISPLAY 1.234043 (-2125 4525);
PAINT GREEN (-2125 4525);
DISPLAY INVISIBLE (-2125 4525);
FORCEPROP 1 LAST PATH I50
J 2
(-1800 4650);
DISPLAY 0.936170 (-1800 4650);
PAINT GREEN (-1800 4650);
DISPLAY INVISIBLE (-1800 4650);
FORCEADD TAP..6
R 2
(-1800 4750);
FORCEPROP 3 LASTPIN (-1850 4750) SIG_NAME M_J_DQ<63>
J 0
(-1840 4760);
DISPLAY 0.659574 (-1840 4760);
PAINT MONO (-1840 4760);
DISPLAY INVISIBLE (-1840 4760);
FORCEPROP 1 LASTPIN (-1850 4750) BN 63
J 2
(-1800 4760);
DISPLAY 0.617021 (-1800 4760);
PAINT PINK (-1800 4760);
FORCEPROP 2 LAST CDS_LIB mstr_standard
J 2
(-1800 4750);
DISPLAY 0.787234 (-1800 4750);
PAINT MONO (-1800 4750);
DISPLAY INVISIBLE (-1800 4750);
FORCEPROP 1 LAST BODY_TYPE PLUMBING
J 2
(-1800 4700);
DISPLAY 1.234043 (-1800 4700);
PAINT GREEN (-1800 4700);
DISPLAY INVISIBLE (-1800 4700);
FORCEPROP 1 LAST HDL_TAP TRUE
J 2
(-2125 4625);
DISPLAY 1.234043 (-2125 4625);
PAINT GREEN (-2125 4625);
DISPLAY INVISIBLE (-2125 4625);
FORCEPROP 1 LAST PATH I51
J 2
(-1800 4750);
DISPLAY 0.936170 (-1800 4750);
PAINT GREEN (-1800 4750);
DISPLAY INVISIBLE (-1800 4750);
FORCEADD TAP..6
R 2
(-1800 4450);
FORCEPROP 3 LASTPIN (-1850 4450) SIG_NAME M_J_DQ<57>
J 0
(-1840 4460);
DISPLAY 0.659574 (-1840 4460);
PAINT MONO (-1840 4460);
DISPLAY INVISIBLE (-1840 4460);
FORCEPROP 1 LASTPIN (-1850 4450) BN 57
J 2
(-1800 4460);
DISPLAY 0.617021 (-1800 4460);
PAINT PINK (-1800 4460);
FORCEPROP 2 LAST CDS_LIB mstr_standard
J 2
(-1800 4450);
DISPLAY 0.787234 (-1800 4450);
PAINT MONO (-1800 4450);
DISPLAY INVISIBLE (-1800 4450);
FORCEPROP 1 LAST BODY_TYPE PLUMBING
J 2
(-1800 4400);
DISPLAY 1.234043 (-1800 4400);
PAINT GREEN (-1800 4400);
DISPLAY INVISIBLE (-1800 4400);
FORCEPROP 1 LAST HDL_TAP TRUE
J 2
(-2125 4325);
DISPLAY 1.234043 (-2125 4325);
PAINT GREEN (-2125 4325);
DISPLAY INVISIBLE (-2125 4325);
FORCEPROP 1 LAST PATH I52
J 2
(-1800 4450);
DISPLAY 0.936170 (-1800 4450);
PAINT GREEN (-1800 4450);
DISPLAY INVISIBLE (-1800 4450);
FORCEADD TAP..6
R 2
(-1800 4400);
FORCEPROP 3 LASTPIN (-1850 4400) SIG_NAME M_J_DQ<54>
J 0
(-1840 4410);
DISPLAY 0.659574 (-1840 4410);
PAINT MONO (-1840 4410);
DISPLAY INVISIBLE (-1840 4410);
FORCEPROP 1 LASTPIN (-1850 4400) BN 54
J 2
(-1800 4410);
DISPLAY 0.617021 (-1800 4410);
PAINT PINK (-1800 4410);
FORCEPROP 2 LAST CDS_LIB mstr_standard
J 2
(-1800 4400);
DISPLAY 0.787234 (-1800 4400);
PAINT MONO (-1800 4400);
DISPLAY INVISIBLE (-1800 4400);
FORCEPROP 1 LAST BODY_TYPE PLUMBING
J 2
(-1800 4350);
DISPLAY 1.234043 (-1800 4350);
PAINT GREEN (-1800 4350);
DISPLAY INVISIBLE (-1800 4350);
FORCEPROP 1 LAST HDL_TAP TRUE
J 2
(-2125 4275);
DISPLAY 1.234043 (-2125 4275);
PAINT GREEN (-2125 4275);
DISPLAY INVISIBLE (-2125 4275);
FORCEPROP 1 LAST PATH I53
J 2
(-1800 4400);
DISPLAY 0.936170 (-1800 4400);
PAINT GREEN (-1800 4400);
DISPLAY INVISIBLE (-1800 4400);
FORCEADD TAP..6
R 2
(-1800 4350);
FORCEPROP 3 LASTPIN (-1850 4350) SIG_NAME M_J_DQ<55>
J 0
(-1840 4360);
DISPLAY 0.659574 (-1840 4360);
PAINT MONO (-1840 4360);
DISPLAY INVISIBLE (-1840 4360);
FORCEPROP 1 LASTPIN (-1850 4350) BN 55
J 2
(-1800 4360);
DISPLAY 0.617021 (-1800 4360);
PAINT PINK (-1800 4360);
FORCEPROP 2 LAST CDS_LIB mstr_standard
J 2
(-1800 4350);
DISPLAY 0.787234 (-1800 4350);
PAINT MONO (-1800 4350);
DISPLAY INVISIBLE (-1800 4350);
FORCEPROP 1 LAST BODY_TYPE PLUMBING
J 2
(-1800 4300);
DISPLAY 1.234043 (-1800 4300);
PAINT GREEN (-1800 4300);
DISPLAY INVISIBLE (-1800 4300);
FORCEPROP 1 LAST HDL_TAP TRUE
J 2
(-2125 4225);
DISPLAY 1.234043 (-2125 4225);
PAINT GREEN (-2125 4225);
DISPLAY INVISIBLE (-2125 4225);
FORCEPROP 1 LAST PATH I54
J 2
(-1800 4350);
DISPLAY 0.936170 (-1800 4350);
PAINT GREEN (-1800 4350);
DISPLAY INVISIBLE (-1800 4350);
FORCEADD TAP..6
R 2
(-1800 4300);
FORCEPROP 3 LASTPIN (-1850 4300) SIG_NAME M_J_DQ<52>
J 0
(-1840 4310);
DISPLAY 0.659574 (-1840 4310);
PAINT MONO (-1840 4310);
DISPLAY INVISIBLE (-1840 4310);
FORCEPROP 1 LASTPIN (-1850 4300) BN 52
J 2
(-1800 4310);
DISPLAY 0.617021 (-1800 4310);
PAINT PINK (-1800 4310);
FORCEPROP 2 LAST CDS_LIB mstr_standard
J 2
(-1800 4300);
DISPLAY 0.787234 (-1800 4300);
PAINT MONO (-1800 4300);
DISPLAY INVISIBLE (-1800 4300);
FORCEPROP 1 LAST BODY_TYPE PLUMBING
J 2
(-1800 4250);
DISPLAY 1.234043 (-1800 4250);
PAINT GREEN (-1800 4250);
DISPLAY INVISIBLE (-1800 4250);
FORCEPROP 1 LAST HDL_TAP TRUE
J 2
(-2125 4175);
DISPLAY 1.234043 (-2125 4175);
PAINT GREEN (-2125 4175);
DISPLAY INVISIBLE (-2125 4175);
FORCEPROP 1 LAST PATH I55
J 2
(-1800 4300);
DISPLAY 0.936170 (-1800 4300);
PAINT GREEN (-1800 4300);
DISPLAY INVISIBLE (-1800 4300);
FORCEADD TAP..6
R 2
(-1800 4500);
FORCEPROP 3 LASTPIN (-1850 4500) SIG_NAME M_J_DQ<56>
J 0
(-1840 4510);
DISPLAY 0.659574 (-1840 4510);
PAINT MONO (-1840 4510);
DISPLAY INVISIBLE (-1840 4510);
FORCEPROP 1 LASTPIN (-1850 4500) BN 56
J 2
(-1800 4510);
DISPLAY 0.617021 (-1800 4510);
PAINT PINK (-1800 4510);
FORCEPROP 2 LAST CDS_LIB mstr_standard
J 2
(-1800 4500);
DISPLAY 0.787234 (-1800 4500);
PAINT MONO (-1800 4500);
DISPLAY INVISIBLE (-1800 4500);
FORCEPROP 1 LAST BODY_TYPE PLUMBING
J 2
(-1800 4450);
DISPLAY 1.234043 (-1800 4450);
PAINT GREEN (-1800 4450);
DISPLAY INVISIBLE (-1800 4450);
FORCEPROP 1 LAST HDL_TAP TRUE
J 2
(-2125 4375);
DISPLAY 1.234043 (-2125 4375);
PAINT GREEN (-2125 4375);
DISPLAY INVISIBLE (-2125 4375);
FORCEPROP 1 LAST PATH I56
J 2
(-1800 4500);
DISPLAY 0.936170 (-1800 4500);
PAINT GREEN (-1800 4500);
DISPLAY INVISIBLE (-1800 4500);
FORCEADD TAP..6
R 2
(-1800 4200);
FORCEPROP 3 LASTPIN (-1850 4200) SIG_NAME M_J_DQ<50>
J 0
(-1840 4210);
DISPLAY 0.659574 (-1840 4210);
PAINT MONO (-1840 4210);
DISPLAY INVISIBLE (-1840 4210);
FORCEPROP 1 LASTPIN (-1850 4200) BN 50
J 2
(-1800 4210);
DISPLAY 0.617021 (-1800 4210);
PAINT PINK (-1800 4210);
FORCEPROP 2 LAST CDS_LIB mstr_standard
J 2
(-1800 4200);
DISPLAY 0.787234 (-1800 4200);
PAINT MONO (-1800 4200);
DISPLAY INVISIBLE (-1800 4200);
FORCEPROP 1 LAST BODY_TYPE PLUMBING
J 2
(-1800 4150);
DISPLAY 1.234043 (-1800 4150);
PAINT GREEN (-1800 4150);
DISPLAY INVISIBLE (-1800 4150);
FORCEPROP 1 LAST HDL_TAP TRUE
J 2
(-2125 4075);
DISPLAY 1.234043 (-2125 4075);
PAINT GREEN (-2125 4075);
DISPLAY INVISIBLE (-2125 4075);
FORCEPROP 1 LAST PATH I57
J 2
(-1800 4200);
DISPLAY 0.936170 (-1800 4200);
PAINT GREEN (-1800 4200);
DISPLAY INVISIBLE (-1800 4200);
FORCEADD TAP..6
R 2
(-1800 4150);
FORCEPROP 3 LASTPIN (-1850 4150) SIG_NAME M_J_DQ<51>
J 0
(-1840 4160);
DISPLAY 0.659574 (-1840 4160);
PAINT MONO (-1840 4160);
DISPLAY INVISIBLE (-1840 4160);
FORCEPROP 1 LASTPIN (-1850 4150) BN 51
J 2
(-1800 4160);
DISPLAY 0.617021 (-1800 4160);
PAINT PINK (-1800 4160);
FORCEPROP 2 LAST CDS_LIB mstr_standard
J 2
(-1800 4150);
DISPLAY 0.787234 (-1800 4150);
PAINT MONO (-1800 4150);
DISPLAY INVISIBLE (-1800 4150);
FORCEPROP 1 LAST BODY_TYPE PLUMBING
J 2
(-1800 4100);
DISPLAY 1.234043 (-1800 4100);
PAINT GREEN (-1800 4100);
DISPLAY INVISIBLE (-1800 4100);
FORCEPROP 1 LAST HDL_TAP TRUE
J 2
(-2125 4025);
DISPLAY 1.234043 (-2125 4025);
PAINT GREEN (-2125 4025);
DISPLAY INVISIBLE (-2125 4025);
FORCEPROP 1 LAST PATH I58
J 2
(-1800 4150);
DISPLAY 0.936170 (-1800 4150);
PAINT GREEN (-1800 4150);
DISPLAY INVISIBLE (-1800 4150);
FORCEADD TAP..6
R 2
(-1800 4100);
FORCEPROP 3 LASTPIN (-1850 4100) SIG_NAME M_J_DQ<48>
J 0
(-1840 4110);
DISPLAY 0.659574 (-1840 4110);
PAINT MONO (-1840 4110);
DISPLAY INVISIBLE (-1840 4110);
FORCEPROP 1 LASTPIN (-1850 4100) BN 48
J 2
(-1800 4110);
DISPLAY 0.617021 (-1800 4110);
PAINT PINK (-1800 4110);
FORCEPROP 2 LAST CDS_LIB mstr_standard
J 2
(-1800 4100);
DISPLAY 0.787234 (-1800 4100);
PAINT MONO (-1800 4100);
DISPLAY INVISIBLE (-1800 4100);
FORCEPROP 1 LAST BODY_TYPE PLUMBING
J 2
(-1800 4050);
DISPLAY 1.234043 (-1800 4050);
PAINT GREEN (-1800 4050);
DISPLAY INVISIBLE (-1800 4050);
FORCEPROP 1 LAST HDL_TAP TRUE
J 2
(-2125 3975);
DISPLAY 1.234043 (-2125 3975);
PAINT GREEN (-2125 3975);
DISPLAY INVISIBLE (-2125 3975);
FORCEPROP 1 LAST PATH I59
J 2
(-1800 4100);
DISPLAY 0.936170 (-1800 4100);
PAINT GREEN (-1800 4100);
DISPLAY INVISIBLE (-1800 4100);
FORCEADD TAP..6
R 2
(650 5050);
FORCEPROP 3 LASTPIN (600 5050) SIG_NAME M_J_DQS_DP<16>
J 0
(610 5060);
DISPLAY 0.659574 (610 5060);
PAINT MONO (610 5060);
DISPLAY INVISIBLE (610 5060);
FORCEPROP 1 LASTPIN (600 5050) BN 16
J 2
(650 5060);
DISPLAY 0.617021 (650 5060);
PAINT PINK (650 5060);
FORCEPROP 2 LAST CDS_LIB mstr_standard
J 0
(650 5050);
DISPLAY 0.787234 (650 5050);
PAINT MONO (650 5050);
DISPLAY INVISIBLE (650 5050);
FORCEPROP 1 LAST BODY_TYPE PLUMBING
J 2
(650 5000);
DISPLAY 1.234043 (650 5000);
PAINT GREEN (650 5000);
DISPLAY INVISIBLE (650 5000);
FORCEPROP 1 LAST HDL_TAP TRUE
J 2
(325 4925);
DISPLAY 1.234043 (325 4925);
PAINT GREEN (325 4925);
DISPLAY INVISIBLE (325 4925);
FORCEPROP 1 LAST PATH I6
J 2
(650 5050);
DISPLAY 0.936170 (650 5050);
PAINT GREEN (650 5050);
DISPLAY INVISIBLE (650 5050);
FORCEADD TAP..6
R 2
(-1800 4050);
FORCEPROP 3 LASTPIN (-1850 4050) SIG_NAME M_J_DQ<49>
J 0
(-1840 4060);
DISPLAY 0.659574 (-1840 4060);
PAINT MONO (-1840 4060);
DISPLAY INVISIBLE (-1840 4060);
FORCEPROP 1 LASTPIN (-1850 4050) BN 49
J 2
(-1800 4060);
DISPLAY 0.617021 (-1800 4060);
PAINT PINK (-1800 4060);
FORCEPROP 2 LAST CDS_LIB mstr_standard
J 2
(-1800 4050);
DISPLAY 0.787234 (-1800 4050);
PAINT MONO (-1800 4050);
DISPLAY INVISIBLE (-1800 4050);
FORCEPROP 1 LAST BODY_TYPE PLUMBING
J 2
(-1800 4000);
DISPLAY 1.234043 (-1800 4000);
PAINT GREEN (-1800 4000);
DISPLAY INVISIBLE (-1800 4000);
FORCEPROP 1 LAST HDL_TAP TRUE
J 2
(-2125 3925);
DISPLAY 1.234043 (-2125 3925);
PAINT GREEN (-2125 3925);
DISPLAY INVISIBLE (-2125 3925);
FORCEPROP 1 LAST PATH I60
J 2
(-1800 4050);
DISPLAY 0.936170 (-1800 4050);
PAINT GREEN (-1800 4050);
DISPLAY INVISIBLE (-1800 4050);
FORCEADD TAP..6
R 2
(-1800 4250);
FORCEPROP 3 LASTPIN (-1850 4250) SIG_NAME M_J_DQ<53>
J 0
(-1840 4260);
DISPLAY 0.659574 (-1840 4260);
PAINT MONO (-1840 4260);
DISPLAY INVISIBLE (-1840 4260);
FORCEPROP 1 LASTPIN (-1850 4250) BN 53
J 2
(-1800 4260);
DISPLAY 0.617021 (-1800 4260);
PAINT PINK (-1800 4260);
FORCEPROP 2 LAST CDS_LIB mstr_standard
J 2
(-1800 4250);
DISPLAY 0.787234 (-1800 4250);
PAINT MONO (-1800 4250);
DISPLAY INVISIBLE (-1800 4250);
FORCEPROP 1 LAST BODY_TYPE PLUMBING
J 2
(-1800 4200);
DISPLAY 1.234043 (-1800 4200);
PAINT GREEN (-1800 4200);
DISPLAY INVISIBLE (-1800 4200);
FORCEPROP 1 LAST HDL_TAP TRUE
J 2
(-2125 4125);
DISPLAY 1.234043 (-2125 4125);
PAINT GREEN (-2125 4125);
DISPLAY INVISIBLE (-2125 4125);
FORCEPROP 1 LAST PATH I61
J 2
(-1800 4250);
DISPLAY 0.936170 (-1800 4250);
PAINT GREEN (-1800 4250);
DISPLAY INVISIBLE (-1800 4250);
FORCEADD TAP..6
R 2
(-1800 3900);
FORCEPROP 3 LASTPIN (-1850 3900) SIG_NAME M_J_DQ<44>
J 0
(-1840 3910);
DISPLAY 0.659574 (-1840 3910);
PAINT MONO (-1840 3910);
DISPLAY INVISIBLE (-1840 3910);
FORCEPROP 1 LASTPIN (-1850 3900) BN 44
J 2
(-1800 3910);
DISPLAY 0.617021 (-1800 3910);
PAINT PINK (-1800 3910);
FORCEPROP 2 LAST CDS_LIB mstr_standard
J 2
(-1800 3900);
DISPLAY 0.787234 (-1800 3900);
PAINT MONO (-1800 3900);
DISPLAY INVISIBLE (-1800 3900);
FORCEPROP 1 LAST BODY_TYPE PLUMBING
J 2
(-1800 3850);
DISPLAY 1.234043 (-1800 3850);
PAINT GREEN (-1800 3850);
DISPLAY INVISIBLE (-1800 3850);
FORCEPROP 1 LAST HDL_TAP TRUE
J 2
(-2125 3775);
DISPLAY 1.234043 (-2125 3775);
PAINT GREEN (-2125 3775);
DISPLAY INVISIBLE (-2125 3775);
FORCEPROP 1 LAST PATH I62
J 2
(-1800 3900);
DISPLAY 0.936170 (-1800 3900);
PAINT GREEN (-1800 3900);
DISPLAY INVISIBLE (-1800 3900);
FORCEADD TAP..6
R 2
(-1800 3850);
FORCEPROP 3 LASTPIN (-1850 3850) SIG_NAME M_J_DQ<45>
J 0
(-1840 3860);
DISPLAY 0.659574 (-1840 3860);
PAINT MONO (-1840 3860);
DISPLAY INVISIBLE (-1840 3860);
FORCEPROP 1 LASTPIN (-1850 3850) BN 45
J 2
(-1800 3860);
DISPLAY 0.617021 (-1800 3860);
PAINT PINK (-1800 3860);
FORCEPROP 2 LAST CDS_LIB mstr_standard
J 2
(-1800 3850);
DISPLAY 0.787234 (-1800 3850);
PAINT MONO (-1800 3850);
DISPLAY INVISIBLE (-1800 3850);
FORCEPROP 1 LAST BODY_TYPE PLUMBING
J 2
(-1800 3800);
DISPLAY 1.234043 (-1800 3800);
PAINT GREEN (-1800 3800);
DISPLAY INVISIBLE (-1800 3800);
FORCEPROP 1 LAST HDL_TAP TRUE
J 2
(-2125 3725);
DISPLAY 1.234043 (-2125 3725);
PAINT GREEN (-2125 3725);
DISPLAY INVISIBLE (-2125 3725);
FORCEPROP 1 LAST PATH I63
J 2
(-1800 3850);
DISPLAY 0.936170 (-1800 3850);
PAINT GREEN (-1800 3850);
DISPLAY INVISIBLE (-1800 3850);
FORCEADD TAP..6
R 2
(-1800 3800);
FORCEPROP 3 LASTPIN (-1850 3800) SIG_NAME M_J_DQ<42>
J 0
(-1840 3810);
DISPLAY 0.659574 (-1840 3810);
PAINT MONO (-1840 3810);
DISPLAY INVISIBLE (-1840 3810);
FORCEPROP 1 LASTPIN (-1850 3800) BN 42
J 2
(-1800 3810);
DISPLAY 0.617021 (-1800 3810);
PAINT PINK (-1800 3810);
FORCEPROP 2 LAST CDS_LIB mstr_standard
J 2
(-1800 3800);
DISPLAY 0.787234 (-1800 3800);
PAINT MONO (-1800 3800);
DISPLAY INVISIBLE (-1800 3800);
FORCEPROP 1 LAST BODY_TYPE PLUMBING
J 2
(-1800 3750);
DISPLAY 1.234043 (-1800 3750);
PAINT GREEN (-1800 3750);
DISPLAY INVISIBLE (-1800 3750);
FORCEPROP 1 LAST HDL_TAP TRUE
J 2
(-2125 3675);
DISPLAY 1.234043 (-2125 3675);
PAINT GREEN (-2125 3675);
DISPLAY INVISIBLE (-2125 3675);
FORCEPROP 1 LAST PATH I64
J 2
(-1800 3800);
DISPLAY 0.936170 (-1800 3800);
PAINT GREEN (-1800 3800);
DISPLAY INVISIBLE (-1800 3800);
FORCEADD TAP..6
R 2
(-1800 3950);
FORCEPROP 3 LASTPIN (-1850 3950) SIG_NAME M_J_DQ<47>
J 0
(-1840 3960);
DISPLAY 0.659574 (-1840 3960);
PAINT MONO (-1840 3960);
DISPLAY INVISIBLE (-1840 3960);
FORCEPROP 1 LASTPIN (-1850 3950) BN 47
J 2
(-1800 3960);
DISPLAY 0.617021 (-1800 3960);
PAINT PINK (-1800 3960);
FORCEPROP 2 LAST CDS_LIB mstr_standard
J 2
(-1800 3950);
DISPLAY 0.787234 (-1800 3950);
PAINT MONO (-1800 3950);
DISPLAY INVISIBLE (-1800 3950);
FORCEPROP 1 LAST BODY_TYPE PLUMBING
J 2
(-1800 3900);
DISPLAY 1.234043 (-1800 3900);
PAINT GREEN (-1800 3900);
DISPLAY INVISIBLE (-1800 3900);
FORCEPROP 1 LAST HDL_TAP TRUE
J 2
(-2125 3825);
DISPLAY 1.234043 (-2125 3825);
PAINT GREEN (-2125 3825);
DISPLAY INVISIBLE (-2125 3825);
FORCEPROP 1 LAST PATH I65
J 2
(-1800 3950);
DISPLAY 0.936170 (-1800 3950);
PAINT GREEN (-1800 3950);
DISPLAY INVISIBLE (-1800 3950);
FORCEADD TAP..6
R 2
(-1800 4000);
FORCEPROP 3 LASTPIN (-1850 4000) SIG_NAME M_J_DQ<46>
J 0
(-1840 4010);
DISPLAY 0.659574 (-1840 4010);
PAINT MONO (-1840 4010);
DISPLAY INVISIBLE (-1840 4010);
FORCEPROP 1 LASTPIN (-1850 4000) BN 46
J 2
(-1800 4010);
DISPLAY 0.617021 (-1800 4010);
PAINT PINK (-1800 4010);
FORCEPROP 2 LAST CDS_LIB mstr_standard
J 2
(-1800 4000);
DISPLAY 0.787234 (-1800 4000);
PAINT MONO (-1800 4000);
DISPLAY INVISIBLE (-1800 4000);
FORCEPROP 1 LAST BODY_TYPE PLUMBING
J 2
(-1800 3950);
DISPLAY 1.234043 (-1800 3950);
PAINT GREEN (-1800 3950);
DISPLAY INVISIBLE (-1800 3950);
FORCEPROP 1 LAST HDL_TAP TRUE
J 2
(-2125 3875);
DISPLAY 1.234043 (-2125 3875);
PAINT GREEN (-2125 3875);
DISPLAY INVISIBLE (-2125 3875);
FORCEPROP 1 LAST PATH I66
J 2
(-1800 4000);
DISPLAY 0.936170 (-1800 4000);
PAINT GREEN (-1800 4000);
DISPLAY INVISIBLE (-1800 4000);
FORCEADD SCONN288_H44441004..2
(-50 4300);
FORCEPROP 1 LAST LOCATION J1G3
J 0
(-450 5400);
DISPLAY 0.617021 (-450 5400);
PAINT AQUA (-450 5400);
FORCEPROP 1 LAST PART_NUMBER H44441-004
J 0
(-450 3200);
DISPLAY 0.617021 (-450 3200);
PAINT BLUE (-450 3200);
FORCEPROP 1 LAST MATERIAL SCONN
J 0
(-450 5350);
DISPLAY 0.617021 (-450 5350);
PAINT SKYBLUE (-450 5350);
FORCEPROP 2 LASTPIN (400 5150) $PN 51
J 0
(410 5160);
DISPLAY 0.617021 (410 5160);
PAINT ORANGE (410 5160);
FORCEPROP 2 LASTPIN (400 5100) $PN 52
J 0
(410 5110);
DISPLAY 0.617021 (410 5110);
PAINT ORANGE (410 5110);
FORCEPROP 2 LASTPIN (400 5050) $PN 132
J 0
(410 5060);
DISPLAY 0.617021 (410 5060);
PAINT ORANGE (410 5060);
FORCEPROP 2 LASTPIN (400 5000) $PN 133
J 0
(410 5010);
DISPLAY 0.617021 (410 5010);
PAINT ORANGE (410 5010);
FORCEPROP 2 LASTPIN (400 4950) $PN 121
J 0
(410 4960);
DISPLAY 0.617021 (410 4960);
PAINT ORANGE (410 4960);
FORCEPROP 2 LASTPIN (400 4900) $PN 122
J 0
(410 4910);
DISPLAY 0.617021 (410 4910);
PAINT ORANGE (410 4910);
FORCEPROP 2 LASTPIN (400 4850) $PN 110
J 0
(410 4860);
DISPLAY 0.617021 (410 4860);
PAINT ORANGE (410 4860);
FORCEPROP 2 LASTPIN (400 4800) $PN 111
J 0
(410 4810);
DISPLAY 0.617021 (410 4810);
PAINT ORANGE (410 4810);
FORCEPROP 2 LASTPIN (400 4750) $PN 99
J 0
(410 4760);
DISPLAY 0.617021 (410 4760);
PAINT ORANGE (410 4760);
FORCEPROP 2 LASTPIN (400 4700) $PN 100
J 0
(410 4710);
DISPLAY 0.617021 (410 4710);
PAINT ORANGE (410 4710);
FORCEPROP 2 LASTPIN (400 4650) $PN 40
J 0
(410 4660);
DISPLAY 0.617021 (410 4660);
PAINT ORANGE (410 4660);
FORCEPROP 2 LASTPIN (400 4600) $PN 41
J 0
(410 4610);
DISPLAY 0.617021 (410 4610);
PAINT ORANGE (410 4610);
FORCEPROP 2 LASTPIN (400 4550) $PN 29
J 0
(410 4560);
DISPLAY 0.617021 (410 4560);
PAINT ORANGE (410 4560);
FORCEPROP 2 LASTPIN (400 4500) $PN 30
J 0
(410 4510);
DISPLAY 0.617021 (410 4510);
PAINT ORANGE (410 4510);
FORCEPROP 2 LASTPIN (400 4450) $PN 18
J 0
(410 4460);
DISPLAY 0.617021 (410 4460);
PAINT ORANGE (410 4460);
FORCEPROP 2 LASTPIN (400 4400) $PN 19
J 0
(410 4410);
DISPLAY 0.617021 (410 4410);
PAINT ORANGE (410 4410);
FORCEPROP 2 LASTPIN (400 4350) $PN 7
J 0
(410 4360);
DISPLAY 0.617021 (410 4360);
PAINT ORANGE (410 4360);
FORCEPROP 2 LASTPIN (400 4300) $PN 8
J 0
(410 4310);
DISPLAY 0.617021 (410 4310);
PAINT ORANGE (410 4310);
FORCEPROP 2 LASTPIN (400 4250) $PN 197
J 0
(410 4260);
DISPLAY 0.617021 (410 4260);
PAINT ORANGE (410 4260);
FORCEPROP 2 LASTPIN (400 4200) $PN 196
J 0
(410 4210);
DISPLAY 0.617021 (410 4210);
PAINT ORANGE (410 4210);
FORCEPROP 2 LASTPIN (400 4150) $PN 278
J 0
(410 4160);
DISPLAY 0.617021 (410 4160);
PAINT ORANGE (410 4160);
FORCEPROP 2 LASTPIN (400 4100) $PN 277
J 0
(410 4110);
DISPLAY 0.617021 (410 4110);
PAINT ORANGE (410 4110);
FORCEPROP 2 LASTPIN (400 4050) $PN 267
J 0
(410 4060);
DISPLAY 0.617021 (410 4060);
PAINT ORANGE (410 4060);
FORCEPROP 2 LASTPIN (400 4000) $PN 266
J 0
(410 4010);
DISPLAY 0.617021 (410 4010);
PAINT ORANGE (410 4010);
FORCEPROP 2 LASTPIN (400 3950) $PN 256
J 0
(410 3960);
DISPLAY 0.617021 (410 3960);
PAINT ORANGE (410 3960);
FORCEPROP 2 LASTPIN (400 3900) $PN 255
J 0
(410 3910);
DISPLAY 0.617021 (410 3910);
PAINT ORANGE (410 3910);
FORCEPROP 2 LASTPIN (400 3850) $PN 245
J 0
(410 3860);
DISPLAY 0.617021 (410 3860);
PAINT ORANGE (410 3860);
FORCEPROP 2 LASTPIN (400 3800) $PN 244
J 0
(410 3810);
DISPLAY 0.617021 (410 3810);
PAINT ORANGE (410 3810);
FORCEPROP 2 LASTPIN (400 3750) $PN 186
J 0
(410 3760);
DISPLAY 0.617021 (410 3760);
PAINT ORANGE (410 3760);
FORCEPROP 2 LASTPIN (400 3700) $PN 185
J 0
(410 3710);
DISPLAY 0.617021 (410 3710);
PAINT ORANGE (410 3710);
FORCEPROP 2 LASTPIN (400 3650) $PN 175
J 0
(410 3660);
DISPLAY 0.617021 (410 3660);
PAINT ORANGE (410 3660);
FORCEPROP 2 LASTPIN (400 3600) $PN 174
J 0
(410 3610);
DISPLAY 0.617021 (410 3610);
PAINT ORANGE (410 3610);
FORCEPROP 2 LASTPIN (400 3550) $PN 164
J 0
(410 3560);
DISPLAY 0.617021 (410 3560);
PAINT ORANGE (410 3560);
FORCEPROP 2 LASTPIN (400 3500) $PN 163
J 0
(410 3510);
DISPLAY 0.617021 (410 3510);
PAINT ORANGE (410 3510);
FORCEPROP 2 LASTPIN (400 3450) $PN 153
J 0
(410 3460);
DISPLAY 0.617021 (410 3460);
PAINT ORANGE (410 3460);
FORCEPROP 2 LASTPIN (400 3400) $PN 152
J 0
(410 3410);
DISPLAY 0.617021 (410 3410);
PAINT ORANGE (410 3410);
FORCEPROP 1 LAST PACK_TYPE PIP
J 0
(-450 5450);
PAINT SKYBLUE (-450 5450);
DISPLAY INVISIBLE (-450 5450);
FORCEPROP 2 LAST BOM_COST MEM
J 0
(-50 4300);
PAINT ORANGE (-50 4300);
DISPLAY INVISIBLE (-50 4300);
FORCEPROP 2 LAST CDS_LIB mstr_sconn
J 0
(-50 4300);
PAINT ORANGE (-50 4300);
DISPLAY INVISIBLE (-50 4300);
FORCEPROP 2 LAST SEC_TYPE PIP
J 0
(-450 5450);
DISPLAY 1.021277 (-450 5450);
PAINT ORANGE (-450 5450);
DISPLAY INVISIBLE (-450 5450);
FORCEPROP 2 LAST SEC 2
J 0
(-450 5450);
DISPLAY 0.680851 (-450 5450);
PAINT MONO (-450 5450);
DISPLAY INVISIBLE (-450 5450);
FORCEPROP 2 LAST CDS_LOCATION J1G3
J 0
(-450 5400);
DISPLAY 0.617021 (-450 5400);
PAINT AQUA (-450 5400);
DISPLAY INVISIBLE (-450 5400);
FORCEPROP 1 LAST PATH I67
J 0
(-50 5350);
PAINT GREEN (-50 5350);
DISPLAY INVISIBLE (-50 5350);
FORCEPROP 2 LAST ROOM DDR4_CH_J
J 0
(-50 4300);
PAINT ORANGE (-50 4300);
DISPLAY INVISIBLE (-50 4300);
FORCEADD TAP..6
R 2
(-1800 3600);
FORCEPROP 3 LASTPIN (-1850 3600) SIG_NAME M_J_DQ<38>
J 0
(-1840 3610);
DISPLAY 0.659574 (-1840 3610);
PAINT MONO (-1840 3610);
DISPLAY INVISIBLE (-1840 3610);
FORCEPROP 1 LASTPIN (-1850 3600) BN 38
J 2
(-1800 3610);
DISPLAY 0.617021 (-1800 3610);
PAINT PINK (-1800 3610);
FORCEPROP 2 LAST CDS_LIB mstr_standard
J 2
(-1800 3600);
DISPLAY 0.787234 (-1800 3600);
PAINT MONO (-1800 3600);
DISPLAY INVISIBLE (-1800 3600);
FORCEPROP 1 LAST BODY_TYPE PLUMBING
J 2
(-1800 3550);
DISPLAY 1.234043 (-1800 3550);
PAINT GREEN (-1800 3550);
DISPLAY INVISIBLE (-1800 3550);
FORCEPROP 1 LAST HDL_TAP TRUE
J 2
(-2125 3475);
DISPLAY 1.234043 (-2125 3475);
PAINT GREEN (-2125 3475);
DISPLAY INVISIBLE (-2125 3475);
FORCEPROP 1 LAST PATH I68
J 2
(-1800 3600);
DISPLAY 0.936170 (-1800 3600);
PAINT GREEN (-1800 3600);
DISPLAY INVISIBLE (-1800 3600);
FORCEADD TAP..6
R 2
(-1800 3650);
FORCEPROP 3 LASTPIN (-1850 3650) SIG_NAME M_J_DQ<41>
J 0
(-1840 3660);
DISPLAY 0.659574 (-1840 3660);
PAINT MONO (-1840 3660);
DISPLAY INVISIBLE (-1840 3660);
FORCEPROP 1 LASTPIN (-1850 3650) BN 41
J 2
(-1800 3660);
DISPLAY 0.617021 (-1800 3660);
PAINT PINK (-1800 3660);
FORCEPROP 2 LAST CDS_LIB mstr_standard
J 2
(-1800 3650);
DISPLAY 0.787234 (-1800 3650);
PAINT MONO (-1800 3650);
DISPLAY INVISIBLE (-1800 3650);
FORCEPROP 1 LAST BODY_TYPE PLUMBING
J 2
(-1800 3600);
DISPLAY 1.234043 (-1800 3600);
PAINT GREEN (-1800 3600);
DISPLAY INVISIBLE (-1800 3600);
FORCEPROP 1 LAST HDL_TAP TRUE
J 2
(-2125 3525);
DISPLAY 1.234043 (-2125 3525);
PAINT GREEN (-2125 3525);
DISPLAY INVISIBLE (-2125 3525);
FORCEPROP 1 LAST PATH I69
J 2
(-1800 3650);
DISPLAY 0.936170 (-1800 3650);
PAINT GREEN (-1800 3650);
DISPLAY INVISIBLE (-1800 3650);
FORCEADD TAP..6
R 2
(850 4800);
FORCEPROP 3 LASTPIN (800 4800) SIG_NAME M_J_DQS_DN<14>
J 0
(810 4810);
DISPLAY 0.659574 (810 4810);
PAINT MONO (810 4810);
DISPLAY INVISIBLE (810 4810);
FORCEPROP 1 LASTPIN (800 4800) BN 14
J 2
(850 4810);
DISPLAY 0.617021 (850 4810);
PAINT PINK (850 4810);
FORCEPROP 2 LAST CDS_LIB mstr_standard
J 0
(850 4800);
DISPLAY 0.787234 (850 4800);
PAINT MONO (850 4800);
DISPLAY INVISIBLE (850 4800);
FORCEPROP 1 LAST BODY_TYPE PLUMBING
J 2
(850 4750);
DISPLAY 1.234043 (850 4750);
PAINT GREEN (850 4750);
DISPLAY INVISIBLE (850 4750);
FORCEPROP 1 LAST HDL_TAP TRUE
J 2
(525 4675);
DISPLAY 1.234043 (525 4675);
PAINT GREEN (525 4675);
DISPLAY INVISIBLE (525 4675);
FORCEPROP 1 LAST PATH I7
J 2
(850 4800);
DISPLAY 0.936170 (850 4800);
PAINT GREEN (850 4800);
DISPLAY INVISIBLE (850 4800);
FORCEADD TAP..6
R 2
(-1800 3550);
FORCEPROP 3 LASTPIN (-1850 3550) SIG_NAME M_J_DQ<39>
J 0
(-1840 3560);
DISPLAY 0.659574 (-1840 3560);
PAINT MONO (-1840 3560);
DISPLAY INVISIBLE (-1840 3560);
FORCEPROP 1 LASTPIN (-1850 3550) BN 39
J 2
(-1800 3560);
DISPLAY 0.617021 (-1800 3560);
PAINT PINK (-1800 3560);
FORCEPROP 2 LAST CDS_LIB mstr_standard
J 2
(-1800 3550);
DISPLAY 0.787234 (-1800 3550);
PAINT MONO (-1800 3550);
DISPLAY INVISIBLE (-1800 3550);
FORCEPROP 1 LAST BODY_TYPE PLUMBING
J 2
(-1800 3500);
DISPLAY 1.234043 (-1800 3500);
PAINT GREEN (-1800 3500);
DISPLAY INVISIBLE (-1800 3500);
FORCEPROP 1 LAST HDL_TAP TRUE
J 2
(-2125 3425);
DISPLAY 1.234043 (-2125 3425);
PAINT GREEN (-2125 3425);
DISPLAY INVISIBLE (-2125 3425);
FORCEPROP 1 LAST PATH I70
J 2
(-1800 3550);
DISPLAY 0.936170 (-1800 3550);
PAINT GREEN (-1800 3550);
DISPLAY INVISIBLE (-1800 3550);
FORCEADD TAP..6
R 2
(-1800 3700);
FORCEPROP 3 LASTPIN (-1850 3700) SIG_NAME M_J_DQ<40>
J 0
(-1840 3710);
DISPLAY 0.659574 (-1840 3710);
PAINT MONO (-1840 3710);
DISPLAY INVISIBLE (-1840 3710);
FORCEPROP 1 LASTPIN (-1850 3700) BN 40
J 2
(-1800 3710);
DISPLAY 0.617021 (-1800 3710);
PAINT PINK (-1800 3710);
FORCEPROP 2 LAST CDS_LIB mstr_standard
J 2
(-1800 3700);
DISPLAY 0.787234 (-1800 3700);
PAINT MONO (-1800 3700);
DISPLAY INVISIBLE (-1800 3700);
FORCEPROP 1 LAST BODY_TYPE PLUMBING
J 2
(-1800 3650);
DISPLAY 1.234043 (-1800 3650);
PAINT GREEN (-1800 3650);
DISPLAY INVISIBLE (-1800 3650);
FORCEPROP 1 LAST HDL_TAP TRUE
J 2
(-2125 3575);
DISPLAY 1.234043 (-2125 3575);
PAINT GREEN (-2125 3575);
DISPLAY INVISIBLE (-2125 3575);
FORCEPROP 1 LAST PATH I71
J 2
(-1800 3700);
DISPLAY 0.936170 (-1800 3700);
PAINT GREEN (-1800 3700);
DISPLAY INVISIBLE (-1800 3700);
FORCEADD TAP..6
R 2
(-1800 3750);
FORCEPROP 3 LASTPIN (-1850 3750) SIG_NAME M_J_DQ<43>
J 0
(-1840 3760);
DISPLAY 0.659574 (-1840 3760);
PAINT MONO (-1840 3760);
DISPLAY INVISIBLE (-1840 3760);
FORCEPROP 1 LASTPIN (-1850 3750) BN 43
J 2
(-1800 3760);
DISPLAY 0.617021 (-1800 3760);
PAINT PINK (-1800 3760);
FORCEPROP 2 LAST CDS_LIB mstr_standard
J 2
(-1800 3750);
DISPLAY 0.787234 (-1800 3750);
PAINT MONO (-1800 3750);
DISPLAY INVISIBLE (-1800 3750);
FORCEPROP 1 LAST BODY_TYPE PLUMBING
J 2
(-1800 3700);
DISPLAY 1.234043 (-1800 3700);
PAINT GREEN (-1800 3700);
DISPLAY INVISIBLE (-1800 3700);
FORCEPROP 1 LAST HDL_TAP TRUE
J 2
(-2125 3625);
DISPLAY 1.234043 (-2125 3625);
PAINT GREEN (-2125 3625);
DISPLAY INVISIBLE (-2125 3625);
FORCEPROP 1 LAST PATH I72
J 2
(-1800 3750);
DISPLAY 0.936170 (-1800 3750);
PAINT GREEN (-1800 3750);
DISPLAY INVISIBLE (-1800 3750);
FORCEADD TAP..6
R 2
(-1800 3350);
FORCEPROP 3 LASTPIN (-1850 3350) SIG_NAME M_J_DQ<35>
J 0
(-1840 3360);
DISPLAY 0.659574 (-1840 3360);
PAINT MONO (-1840 3360);
DISPLAY INVISIBLE (-1840 3360);
FORCEPROP 1 LASTPIN (-1850 3350) BN 35
J 2
(-1800 3360);
DISPLAY 0.617021 (-1800 3360);
PAINT PINK (-1800 3360);
FORCEPROP 2 LAST CDS_LIB mstr_standard
J 2
(-1800 3350);
DISPLAY 0.787234 (-1800 3350);
PAINT MONO (-1800 3350);
DISPLAY INVISIBLE (-1800 3350);
FORCEPROP 1 LAST BODY_TYPE PLUMBING
J 2
(-1800 3300);
DISPLAY 1.234043 (-1800 3300);
PAINT GREEN (-1800 3300);
DISPLAY INVISIBLE (-1800 3300);
FORCEPROP 1 LAST HDL_TAP TRUE
J 2
(-2125 3225);
DISPLAY 1.234043 (-2125 3225);
PAINT GREEN (-2125 3225);
DISPLAY INVISIBLE (-2125 3225);
FORCEPROP 1 LAST PATH I73
J 2
(-1800 3350);
DISPLAY 0.936170 (-1800 3350);
PAINT GREEN (-1800 3350);
DISPLAY INVISIBLE (-1800 3350);
FORCEADD TAP..6
R 2
(-1800 3400);
FORCEPROP 3 LASTPIN (-1850 3400) SIG_NAME M_J_DQ<34>
J 0
(-1840 3410);
DISPLAY 0.659574 (-1840 3410);
PAINT MONO (-1840 3410);
DISPLAY INVISIBLE (-1840 3410);
FORCEPROP 1 LASTPIN (-1850 3400) BN 34
J 2
(-1800 3410);
DISPLAY 0.617021 (-1800 3410);
PAINT PINK (-1800 3410);
FORCEPROP 2 LAST CDS_LIB mstr_standard
J 2
(-1800 3400);
DISPLAY 0.787234 (-1800 3400);
PAINT MONO (-1800 3400);
DISPLAY INVISIBLE (-1800 3400);
FORCEPROP 1 LAST BODY_TYPE PLUMBING
J 2
(-1800 3350);
DISPLAY 1.234043 (-1800 3350);
PAINT GREEN (-1800 3350);
DISPLAY INVISIBLE (-1800 3350);
FORCEPROP 1 LAST HDL_TAP TRUE
J 2
(-2125 3275);
DISPLAY 1.234043 (-2125 3275);
PAINT GREEN (-2125 3275);
DISPLAY INVISIBLE (-2125 3275);
FORCEPROP 1 LAST PATH I74
J 2
(-1800 3400);
DISPLAY 0.936170 (-1800 3400);
PAINT GREEN (-1800 3400);
DISPLAY INVISIBLE (-1800 3400);
FORCEADD TAP..6
R 2
(-1800 3300);
FORCEPROP 3 LASTPIN (-1850 3300) SIG_NAME M_J_DQ<32>
J 0
(-1840 3310);
DISPLAY 0.659574 (-1840 3310);
PAINT MONO (-1840 3310);
DISPLAY INVISIBLE (-1840 3310);
FORCEPROP 1 LASTPIN (-1850 3300) BN 32
J 2
(-1800 3310);
DISPLAY 0.617021 (-1800 3310);
PAINT PINK (-1800 3310);
FORCEPROP 2 LAST CDS_LIB mstr_standard
J 2
(-1800 3300);
DISPLAY 0.787234 (-1800 3300);
PAINT MONO (-1800 3300);
DISPLAY INVISIBLE (-1800 3300);
FORCEPROP 1 LAST BODY_TYPE PLUMBING
J 2
(-1800 3250);
DISPLAY 1.234043 (-1800 3250);
PAINT GREEN (-1800 3250);
DISPLAY INVISIBLE (-1800 3250);
FORCEPROP 1 LAST HDL_TAP TRUE
J 2
(-2125 3175);
DISPLAY 1.234043 (-2125 3175);
PAINT GREEN (-2125 3175);
DISPLAY INVISIBLE (-2125 3175);
FORCEPROP 1 LAST PATH I75
J 2
(-1800 3300);
DISPLAY 0.936170 (-1800 3300);
PAINT GREEN (-1800 3300);
DISPLAY INVISIBLE (-1800 3300);
FORCEADD TAP..6
R 2
(-1800 3450);
FORCEPROP 3 LASTPIN (-1850 3450) SIG_NAME M_J_DQ<37>
J 0
(-1840 3460);
DISPLAY 0.659574 (-1840 3460);
PAINT MONO (-1840 3460);
DISPLAY INVISIBLE (-1840 3460);
FORCEPROP 1 LASTPIN (-1850 3450) BN 37
J 2
(-1800 3460);
DISPLAY 0.617021 (-1800 3460);
PAINT PINK (-1800 3460);
FORCEPROP 2 LAST CDS_LIB mstr_standard
J 2
(-1800 3450);
DISPLAY 0.787234 (-1800 3450);
PAINT MONO (-1800 3450);
DISPLAY INVISIBLE (-1800 3450);
FORCEPROP 1 LAST BODY_TYPE PLUMBING
J 2
(-1800 3400);
DISPLAY 1.234043 (-1800 3400);
PAINT GREEN (-1800 3400);
DISPLAY INVISIBLE (-1800 3400);
FORCEPROP 1 LAST HDL_TAP TRUE
J 2
(-2125 3325);
DISPLAY 1.234043 (-2125 3325);
PAINT GREEN (-2125 3325);
DISPLAY INVISIBLE (-2125 3325);
FORCEPROP 1 LAST PATH I76
J 2
(-1800 3450);
DISPLAY 0.936170 (-1800 3450);
PAINT GREEN (-1800 3450);
DISPLAY INVISIBLE (-1800 3450);
FORCEADD TAP..6
R 2
(-1800 3500);
FORCEPROP 3 LASTPIN (-1850 3500) SIG_NAME M_J_DQ<36>
J 0
(-1840 3510);
DISPLAY 0.659574 (-1840 3510);
PAINT MONO (-1840 3510);
DISPLAY INVISIBLE (-1840 3510);
FORCEPROP 1 LASTPIN (-1850 3500) BN 36
J 2
(-1800 3510);
DISPLAY 0.617021 (-1800 3510);
PAINT PINK (-1800 3510);
FORCEPROP 2 LAST CDS_LIB mstr_standard
J 2
(-1800 3500);
DISPLAY 0.787234 (-1800 3500);
PAINT MONO (-1800 3500);
DISPLAY INVISIBLE (-1800 3500);
FORCEPROP 1 LAST BODY_TYPE PLUMBING
J 2
(-1800 3450);
DISPLAY 1.234043 (-1800 3450);
PAINT GREEN (-1800 3450);
DISPLAY INVISIBLE (-1800 3450);
FORCEPROP 1 LAST HDL_TAP TRUE
J 2
(-2125 3375);
DISPLAY 1.234043 (-2125 3375);
PAINT GREEN (-2125 3375);
DISPLAY INVISIBLE (-2125 3375);
FORCEPROP 1 LAST PATH I77
J 2
(-1800 3500);
DISPLAY 0.936170 (-1800 3500);
PAINT GREEN (-1800 3500);
DISPLAY INVISIBLE (-1800 3500);
FORCEADD TAP..6
R 2
(-1800 3150);
FORCEPROP 3 LASTPIN (-1850 3150) SIG_NAME M_J_DQ<31>
J 0
(-1840 3160);
DISPLAY 0.659574 (-1840 3160);
PAINT MONO (-1840 3160);
DISPLAY INVISIBLE (-1840 3160);
FORCEPROP 1 LASTPIN (-1850 3150) BN 31
J 2
(-1800 3160);
DISPLAY 0.617021 (-1800 3160);
PAINT PINK (-1800 3160);
FORCEPROP 2 LAST CDS_LIB mstr_standard
J 2
(-1800 3150);
DISPLAY 0.787234 (-1800 3150);
PAINT MONO (-1800 3150);
DISPLAY INVISIBLE (-1800 3150);
FORCEPROP 1 LAST BODY_TYPE PLUMBING
J 2
(-1800 3100);
DISPLAY 1.234043 (-1800 3100);
PAINT GREEN (-1800 3100);
DISPLAY INVISIBLE (-1800 3100);
FORCEPROP 1 LAST HDL_TAP TRUE
J 2
(-2125 3025);
DISPLAY 1.234043 (-2125 3025);
PAINT GREEN (-2125 3025);
DISPLAY INVISIBLE (-2125 3025);
FORCEPROP 1 LAST PATH I78
J 2
(-1800 3150);
DISPLAY 0.936170 (-1800 3150);
PAINT GREEN (-1800 3150);
DISPLAY INVISIBLE (-1800 3150);
FORCEADD TAP..6
R 2
(-1800 3100);
FORCEPROP 3 LASTPIN (-1850 3100) SIG_NAME M_J_DQ<28>
J 0
(-1840 3110);
DISPLAY 0.659574 (-1840 3110);
PAINT MONO (-1840 3110);
DISPLAY INVISIBLE (-1840 3110);
FORCEPROP 1 LASTPIN (-1850 3100) BN 28
J 2
(-1800 3110);
DISPLAY 0.617021 (-1800 3110);
PAINT PINK (-1800 3110);
FORCEPROP 2 LAST CDS_LIB mstr_standard
J 2
(-1800 3100);
DISPLAY 0.787234 (-1800 3100);
PAINT MONO (-1800 3100);
DISPLAY INVISIBLE (-1800 3100);
FORCEPROP 1 LAST BODY_TYPE PLUMBING
J 2
(-1800 3050);
DISPLAY 1.234043 (-1800 3050);
PAINT GREEN (-1800 3050);
DISPLAY INVISIBLE (-1800 3050);
FORCEPROP 1 LAST HDL_TAP TRUE
J 2
(-2125 2975);
DISPLAY 1.234043 (-2125 2975);
PAINT GREEN (-2125 2975);
DISPLAY INVISIBLE (-2125 2975);
FORCEPROP 1 LAST PATH I79
J 2
(-1800 3100);
DISPLAY 0.936170 (-1800 3100);
PAINT GREEN (-1800 3100);
DISPLAY INVISIBLE (-1800 3100);
FORCEADD TAP..6
R 2
(850 4900);
FORCEPROP 3 LASTPIN (800 4900) SIG_NAME M_J_DQS_DN<15>
J 0
(810 4910);
DISPLAY 0.659574 (810 4910);
PAINT MONO (810 4910);
DISPLAY INVISIBLE (810 4910);
FORCEPROP 1 LASTPIN (800 4900) BN 15
J 2
(850 4910);
DISPLAY 0.617021 (850 4910);
PAINT PINK (850 4910);
FORCEPROP 2 LAST CDS_LIB mstr_standard
J 0
(850 4900);
DISPLAY 0.787234 (850 4900);
PAINT MONO (850 4900);
DISPLAY INVISIBLE (850 4900);
FORCEPROP 1 LAST BODY_TYPE PLUMBING
J 2
(850 4850);
DISPLAY 1.234043 (850 4850);
PAINT GREEN (850 4850);
DISPLAY INVISIBLE (850 4850);
FORCEPROP 1 LAST HDL_TAP TRUE
J 2
(525 4775);
DISPLAY 1.234043 (525 4775);
PAINT GREEN (525 4775);
DISPLAY INVISIBLE (525 4775);
FORCEPROP 1 LAST PATH I8
J 2
(850 4900);
DISPLAY 0.936170 (850 4900);
PAINT GREEN (850 4900);
DISPLAY INVISIBLE (850 4900);
FORCEADD TAP..6
R 2
(-1800 3050);
FORCEPROP 3 LASTPIN (-1850 3050) SIG_NAME M_J_DQ<29>
J 0
(-1840 3060);
DISPLAY 0.659574 (-1840 3060);
PAINT MONO (-1840 3060);
DISPLAY INVISIBLE (-1840 3060);
FORCEPROP 1 LASTPIN (-1850 3050) BN 29
J 2
(-1800 3060);
DISPLAY 0.617021 (-1800 3060);
PAINT PINK (-1800 3060);
FORCEPROP 2 LAST CDS_LIB mstr_standard
J 2
(-1800 3050);
DISPLAY 0.787234 (-1800 3050);
PAINT MONO (-1800 3050);
DISPLAY INVISIBLE (-1800 3050);
FORCEPROP 1 LAST BODY_TYPE PLUMBING
J 2
(-1800 3000);
DISPLAY 1.234043 (-1800 3000);
PAINT GREEN (-1800 3000);
DISPLAY INVISIBLE (-1800 3000);
FORCEPROP 1 LAST HDL_TAP TRUE
J 2
(-2125 2925);
DISPLAY 1.234043 (-2125 2925);
PAINT GREEN (-2125 2925);
DISPLAY INVISIBLE (-2125 2925);
FORCEPROP 1 LAST PATH I80
J 2
(-1800 3050);
DISPLAY 0.936170 (-1800 3050);
PAINT GREEN (-1800 3050);
DISPLAY INVISIBLE (-1800 3050);
FORCEADD TAP..6
R 2
(-1800 3200);
FORCEPROP 3 LASTPIN (-1850 3200) SIG_NAME M_J_DQ<30>
J 0
(-1840 3210);
DISPLAY 0.659574 (-1840 3210);
PAINT MONO (-1840 3210);
DISPLAY INVISIBLE (-1840 3210);
FORCEPROP 1 LASTPIN (-1850 3200) BN 30
J 2
(-1800 3210);
DISPLAY 0.617021 (-1800 3210);
PAINT PINK (-1800 3210);
FORCEPROP 2 LAST CDS_LIB mstr_standard
J 2
(-1800 3200);
DISPLAY 0.787234 (-1800 3200);
PAINT MONO (-1800 3200);
DISPLAY INVISIBLE (-1800 3200);
FORCEPROP 1 LAST BODY_TYPE PLUMBING
J 2
(-1800 3150);
DISPLAY 1.234043 (-1800 3150);
PAINT GREEN (-1800 3150);
DISPLAY INVISIBLE (-1800 3150);
FORCEPROP 1 LAST HDL_TAP TRUE
J 2
(-2125 3075);
DISPLAY 1.234043 (-2125 3075);
PAINT GREEN (-2125 3075);
DISPLAY INVISIBLE (-2125 3075);
FORCEPROP 1 LAST PATH I81
J 2
(-1800 3200);
DISPLAY 0.936170 (-1800 3200);
PAINT GREEN (-1800 3200);
DISPLAY INVISIBLE (-1800 3200);
FORCEADD TAP..6
R 2
(-1800 3250);
FORCEPROP 3 LASTPIN (-1850 3250) SIG_NAME M_J_DQ<33>
J 0
(-1840 3260);
DISPLAY 0.659574 (-1840 3260);
PAINT MONO (-1840 3260);
DISPLAY INVISIBLE (-1840 3260);
FORCEPROP 1 LASTPIN (-1850 3250) BN 33
J 2
(-1800 3260);
DISPLAY 0.617021 (-1800 3260);
PAINT PINK (-1800 3260);
FORCEPROP 2 LAST CDS_LIB mstr_standard
J 2
(-1800 3250);
DISPLAY 0.787234 (-1800 3250);
PAINT MONO (-1800 3250);
DISPLAY INVISIBLE (-1800 3250);
FORCEPROP 1 LAST BODY_TYPE PLUMBING
J 2
(-1800 3200);
DISPLAY 1.234043 (-1800 3200);
PAINT GREEN (-1800 3200);
DISPLAY INVISIBLE (-1800 3200);
FORCEPROP 1 LAST HDL_TAP TRUE
J 2
(-2125 3125);
DISPLAY 1.234043 (-2125 3125);
PAINT GREEN (-2125 3125);
DISPLAY INVISIBLE (-2125 3125);
FORCEPROP 1 LAST PATH I82
J 2
(-1800 3250);
DISPLAY 0.936170 (-1800 3250);
PAINT GREEN (-1800 3250);
DISPLAY INVISIBLE (-1800 3250);
FORCEADD TAP..6
R 2
(-1800 2850);
FORCEPROP 3 LASTPIN (-1850 2850) SIG_NAME M_J_DQ<25>
J 0
(-1840 2860);
DISPLAY 0.659574 (-1840 2860);
PAINT MONO (-1840 2860);
DISPLAY INVISIBLE (-1840 2860);
FORCEPROP 1 LASTPIN (-1850 2850) BN 25
J 2
(-1800 2860);
DISPLAY 0.617021 (-1800 2860);
PAINT PINK (-1800 2860);
FORCEPROP 2 LAST CDS_LIB mstr_standard
J 2
(-1800 2850);
DISPLAY 0.787234 (-1800 2850);
PAINT MONO (-1800 2850);
DISPLAY INVISIBLE (-1800 2850);
FORCEPROP 1 LAST BODY_TYPE PLUMBING
J 2
(-1800 2800);
DISPLAY 1.234043 (-1800 2800);
PAINT GREEN (-1800 2800);
DISPLAY INVISIBLE (-1800 2800);
FORCEPROP 1 LAST HDL_TAP TRUE
J 2
(-2125 2725);
DISPLAY 1.234043 (-2125 2725);
PAINT GREEN (-2125 2725);
DISPLAY INVISIBLE (-2125 2725);
FORCEPROP 1 LAST PATH I83
J 2
(-1800 2850);
DISPLAY 0.936170 (-1800 2850);
PAINT GREEN (-1800 2850);
DISPLAY INVISIBLE (-1800 2850);
FORCEADD TAP..6
R 2
(-1800 2900);
FORCEPROP 3 LASTPIN (-1850 2900) SIG_NAME M_J_DQ<24>
J 0
(-1840 2910);
DISPLAY 0.659574 (-1840 2910);
PAINT MONO (-1840 2910);
DISPLAY INVISIBLE (-1840 2910);
FORCEPROP 1 LASTPIN (-1850 2900) BN 24
J 2
(-1800 2910);
DISPLAY 0.617021 (-1800 2910);
PAINT PINK (-1800 2910);
FORCEPROP 2 LAST CDS_LIB mstr_standard
J 2
(-1800 2900);
DISPLAY 0.787234 (-1800 2900);
PAINT MONO (-1800 2900);
DISPLAY INVISIBLE (-1800 2900);
FORCEPROP 1 LAST BODY_TYPE PLUMBING
J 2
(-1800 2850);
DISPLAY 1.234043 (-1800 2850);
PAINT GREEN (-1800 2850);
DISPLAY INVISIBLE (-1800 2850);
FORCEPROP 1 LAST HDL_TAP TRUE
J 2
(-2125 2775);
DISPLAY 1.234043 (-2125 2775);
PAINT GREEN (-2125 2775);
DISPLAY INVISIBLE (-2125 2775);
FORCEPROP 1 LAST PATH I84
J 2
(-1800 2900);
DISPLAY 0.936170 (-1800 2900);
PAINT GREEN (-1800 2900);
DISPLAY INVISIBLE (-1800 2900);
FORCEADD TAP..6
R 2
(-1800 2800);
FORCEPROP 3 LASTPIN (-1850 2800) SIG_NAME M_J_DQ<22>
J 0
(-1840 2810);
DISPLAY 0.659574 (-1840 2810);
PAINT MONO (-1840 2810);
DISPLAY INVISIBLE (-1840 2810);
FORCEPROP 1 LASTPIN (-1850 2800) BN 22
J 2
(-1800 2810);
DISPLAY 0.617021 (-1800 2810);
PAINT PINK (-1800 2810);
FORCEPROP 2 LAST CDS_LIB mstr_standard
J 2
(-1800 2800);
DISPLAY 0.787234 (-1800 2800);
PAINT MONO (-1800 2800);
DISPLAY INVISIBLE (-1800 2800);
FORCEPROP 1 LAST BODY_TYPE PLUMBING
J 2
(-1800 2750);
DISPLAY 1.234043 (-1800 2750);
PAINT GREEN (-1800 2750);
DISPLAY INVISIBLE (-1800 2750);
FORCEPROP 1 LAST HDL_TAP TRUE
J 2
(-2125 2675);
DISPLAY 1.234043 (-2125 2675);
PAINT GREEN (-2125 2675);
DISPLAY INVISIBLE (-2125 2675);
FORCEPROP 1 LAST PATH I85
J 2
(-1800 2800);
DISPLAY 0.936170 (-1800 2800);
PAINT GREEN (-1800 2800);
DISPLAY INVISIBLE (-1800 2800);
FORCEADD TAP..6
R 2
(-1800 2750);
FORCEPROP 3 LASTPIN (-1850 2750) SIG_NAME M_J_DQ<23>
J 0
(-1840 2760);
DISPLAY 0.659574 (-1840 2760);
PAINT MONO (-1840 2760);
DISPLAY INVISIBLE (-1840 2760);
FORCEPROP 1 LASTPIN (-1850 2750) BN 23
J 2
(-1800 2760);
DISPLAY 0.617021 (-1800 2760);
PAINT PINK (-1800 2760);
FORCEPROP 2 LAST CDS_LIB mstr_standard
J 2
(-1800 2750);
DISPLAY 0.787234 (-1800 2750);
PAINT MONO (-1800 2750);
DISPLAY INVISIBLE (-1800 2750);
FORCEPROP 1 LAST BODY_TYPE PLUMBING
J 2
(-1800 2700);
DISPLAY 1.234043 (-1800 2700);
PAINT GREEN (-1800 2700);
DISPLAY INVISIBLE (-1800 2700);
FORCEPROP 1 LAST HDL_TAP TRUE
J 2
(-2125 2625);
DISPLAY 1.234043 (-2125 2625);
PAINT GREEN (-2125 2625);
DISPLAY INVISIBLE (-2125 2625);
FORCEPROP 1 LAST PATH I86
J 2
(-1800 2750);
DISPLAY 0.936170 (-1800 2750);
PAINT GREEN (-1800 2750);
DISPLAY INVISIBLE (-1800 2750);
FORCEADD TAP..6
R 2
(-1800 2950);
FORCEPROP 3 LASTPIN (-1850 2950) SIG_NAME M_J_DQ<27>
J 0
(-1840 2960);
DISPLAY 0.659574 (-1840 2960);
PAINT MONO (-1840 2960);
DISPLAY INVISIBLE (-1840 2960);
FORCEPROP 1 LASTPIN (-1850 2950) BN 27
J 2
(-1800 2960);
DISPLAY 0.617021 (-1800 2960);
PAINT PINK (-1800 2960);
FORCEPROP 2 LAST CDS_LIB mstr_standard
J 2
(-1800 2950);
DISPLAY 0.787234 (-1800 2950);
PAINT MONO (-1800 2950);
DISPLAY INVISIBLE (-1800 2950);
FORCEPROP 1 LAST BODY_TYPE PLUMBING
J 2
(-1800 2900);
DISPLAY 1.234043 (-1800 2900);
PAINT GREEN (-1800 2900);
DISPLAY INVISIBLE (-1800 2900);
FORCEPROP 1 LAST HDL_TAP TRUE
J 2
(-2125 2825);
DISPLAY 1.234043 (-2125 2825);
PAINT GREEN (-2125 2825);
DISPLAY INVISIBLE (-2125 2825);
FORCEPROP 1 LAST PATH I87
J 2
(-1800 2950);
DISPLAY 0.936170 (-1800 2950);
PAINT GREEN (-1800 2950);
DISPLAY INVISIBLE (-1800 2950);
FORCEADD TAP..6
R 2
(-1800 3000);
FORCEPROP 3 LASTPIN (-1850 3000) SIG_NAME M_J_DQ<26>
J 0
(-1840 3010);
DISPLAY 0.659574 (-1840 3010);
PAINT MONO (-1840 3010);
DISPLAY INVISIBLE (-1840 3010);
FORCEPROP 1 LASTPIN (-1850 3000) BN 26
J 2
(-1800 3010);
DISPLAY 0.617021 (-1800 3010);
PAINT PINK (-1800 3010);
FORCEPROP 2 LAST CDS_LIB mstr_standard
J 2
(-1800 3000);
DISPLAY 0.787234 (-1800 3000);
PAINT MONO (-1800 3000);
DISPLAY INVISIBLE (-1800 3000);
FORCEPROP 1 LAST BODY_TYPE PLUMBING
J 2
(-1800 2950);
DISPLAY 1.234043 (-1800 2950);
PAINT GREEN (-1800 2950);
DISPLAY INVISIBLE (-1800 2950);
FORCEPROP 1 LAST HDL_TAP TRUE
J 2
(-2125 2875);
DISPLAY 1.234043 (-2125 2875);
PAINT GREEN (-2125 2875);
DISPLAY INVISIBLE (-2125 2875);
FORCEPROP 1 LAST PATH I88
J 2
(-1800 3000);
DISPLAY 0.936170 (-1800 3000);
PAINT GREEN (-1800 3000);
DISPLAY INVISIBLE (-1800 3000);
FORCEADD TAP..6
R 2
(-1800 2650);
FORCEPROP 3 LASTPIN (-1850 2650) SIG_NAME M_J_DQ<21>
J 0
(-1840 2660);
DISPLAY 0.659574 (-1840 2660);
PAINT MONO (-1840 2660);
DISPLAY INVISIBLE (-1840 2660);
FORCEPROP 1 LASTPIN (-1850 2650) BN 21
J 2
(-1800 2660);
DISPLAY 0.617021 (-1800 2660);
PAINT PINK (-1800 2660);
FORCEPROP 2 LAST CDS_LIB mstr_standard
J 2
(-1800 2650);
DISPLAY 0.787234 (-1800 2650);
PAINT MONO (-1800 2650);
DISPLAY INVISIBLE (-1800 2650);
FORCEPROP 1 LAST BODY_TYPE PLUMBING
J 2
(-1800 2600);
DISPLAY 1.234043 (-1800 2600);
PAINT GREEN (-1800 2600);
DISPLAY INVISIBLE (-1800 2600);
FORCEPROP 1 LAST HDL_TAP TRUE
J 2
(-2125 2525);
DISPLAY 1.234043 (-2125 2525);
PAINT GREEN (-2125 2525);
DISPLAY INVISIBLE (-2125 2525);
FORCEPROP 1 LAST PATH I89
J 2
(-1800 2650);
DISPLAY 0.936170 (-1800 2650);
PAINT GREEN (-1800 2650);
DISPLAY INVISIBLE (-1800 2650);
FORCEADD TAP..6
R 2
(850 4600);
FORCEPROP 3 LASTPIN (800 4600) SIG_NAME M_J_DQS_DN<12>
J 0
(810 4610);
DISPLAY 0.659574 (810 4610);
PAINT MONO (810 4610);
DISPLAY INVISIBLE (810 4610);
FORCEPROP 1 LASTPIN (800 4600) BN 12
J 2
(850 4610);
DISPLAY 0.617021 (850 4610);
PAINT PINK (850 4610);
FORCEPROP 2 LAST CDS_LIB mstr_standard
J 0
(850 4600);
DISPLAY 0.787234 (850 4600);
PAINT MONO (850 4600);
DISPLAY INVISIBLE (850 4600);
FORCEPROP 1 LAST BODY_TYPE PLUMBING
J 2
(850 4550);
DISPLAY 1.234043 (850 4550);
PAINT GREEN (850 4550);
DISPLAY INVISIBLE (850 4550);
FORCEPROP 1 LAST HDL_TAP TRUE
J 2
(525 4475);
DISPLAY 1.234043 (525 4475);
PAINT GREEN (525 4475);
DISPLAY INVISIBLE (525 4475);
FORCEPROP 1 LAST PATH I9
J 2
(850 4600);
DISPLAY 0.936170 (850 4600);
PAINT GREEN (850 4600);
DISPLAY INVISIBLE (850 4600);
FORCEADD TAP..6
R 2
(-1800 2600);
FORCEPROP 3 LASTPIN (-1850 2600) SIG_NAME M_J_DQ<18>
J 0
(-1840 2610);
DISPLAY 0.659574 (-1840 2610);
PAINT MONO (-1840 2610);
DISPLAY INVISIBLE (-1840 2610);
FORCEPROP 1 LASTPIN (-1850 2600) BN 18
J 2
(-1800 2610);
DISPLAY 0.617021 (-1800 2610);
PAINT PINK (-1800 2610);
FORCEPROP 2 LAST CDS_LIB mstr_standard
J 2
(-1800 2600);
DISPLAY 0.787234 (-1800 2600);
PAINT MONO (-1800 2600);
DISPLAY INVISIBLE (-1800 2600);
FORCEPROP 1 LAST BODY_TYPE PLUMBING
J 2
(-1800 2550);
DISPLAY 1.234043 (-1800 2550);
PAINT GREEN (-1800 2550);
DISPLAY INVISIBLE (-1800 2550);
FORCEPROP 1 LAST HDL_TAP TRUE
J 2
(-2125 2475);
DISPLAY 1.234043 (-2125 2475);
PAINT GREEN (-2125 2475);
DISPLAY INVISIBLE (-2125 2475);
FORCEPROP 1 LAST PATH I90
J 2
(-1800 2600);
DISPLAY 0.936170 (-1800 2600);
PAINT GREEN (-1800 2600);
DISPLAY INVISIBLE (-1800 2600);
FORCEADD TAP..6
R 2
(-1800 2550);
FORCEPROP 3 LASTPIN (-1850 2550) SIG_NAME M_J_DQ<19>
J 0
(-1840 2560);
DISPLAY 0.659574 (-1840 2560);
PAINT MONO (-1840 2560);
DISPLAY INVISIBLE (-1840 2560);
FORCEPROP 1 LASTPIN (-1850 2550) BN 19
J 2
(-1800 2560);
DISPLAY 0.617021 (-1800 2560);
PAINT PINK (-1800 2560);
FORCEPROP 2 LAST CDS_LIB mstr_standard
J 2
(-1800 2550);
DISPLAY 0.787234 (-1800 2550);
PAINT MONO (-1800 2550);
DISPLAY INVISIBLE (-1800 2550);
FORCEPROP 1 LAST BODY_TYPE PLUMBING
J 2
(-1800 2500);
DISPLAY 1.234043 (-1800 2500);
PAINT GREEN (-1800 2500);
DISPLAY INVISIBLE (-1800 2500);
FORCEPROP 1 LAST HDL_TAP TRUE
J 2
(-2125 2425);
DISPLAY 1.234043 (-2125 2425);
PAINT GREEN (-2125 2425);
DISPLAY INVISIBLE (-2125 2425);
FORCEPROP 1 LAST PATH I91
J 2
(-1800 2550);
DISPLAY 0.936170 (-1800 2550);
PAINT GREEN (-1800 2550);
DISPLAY INVISIBLE (-1800 2550);
FORCEADD TAP..6
R 2
(-1800 2500);
FORCEPROP 3 LASTPIN (-1850 2500) SIG_NAME M_J_DQ<16>
J 0
(-1840 2510);
DISPLAY 0.659574 (-1840 2510);
PAINT MONO (-1840 2510);
DISPLAY INVISIBLE (-1840 2510);
FORCEPROP 1 LASTPIN (-1850 2500) BN 16
J 2
(-1800 2510);
DISPLAY 0.617021 (-1800 2510);
PAINT PINK (-1800 2510);
FORCEPROP 2 LAST CDS_LIB mstr_standard
J 2
(-1800 2500);
DISPLAY 0.787234 (-1800 2500);
PAINT MONO (-1800 2500);
DISPLAY INVISIBLE (-1800 2500);
FORCEPROP 1 LAST BODY_TYPE PLUMBING
J 2
(-1800 2450);
DISPLAY 1.234043 (-1800 2450);
PAINT GREEN (-1800 2450);
DISPLAY INVISIBLE (-1800 2450);
FORCEPROP 1 LAST HDL_TAP TRUE
J 2
(-2125 2375);
DISPLAY 1.234043 (-2125 2375);
PAINT GREEN (-2125 2375);
DISPLAY INVISIBLE (-2125 2375);
FORCEPROP 1 LAST PATH I92
J 2
(-1800 2500);
DISPLAY 0.936170 (-1800 2500);
PAINT GREEN (-1800 2500);
DISPLAY INVISIBLE (-1800 2500);
FORCEADD TAP..6
R 2
(-1800 2700);
FORCEPROP 3 LASTPIN (-1850 2700) SIG_NAME M_J_DQ<20>
J 0
(-1840 2710);
DISPLAY 0.659574 (-1840 2710);
PAINT MONO (-1840 2710);
DISPLAY INVISIBLE (-1840 2710);
FORCEPROP 1 LASTPIN (-1850 2700) BN 20
J 2
(-1800 2710);
DISPLAY 0.617021 (-1800 2710);
PAINT PINK (-1800 2710);
FORCEPROP 2 LAST CDS_LIB mstr_standard
J 2
(-1800 2700);
DISPLAY 0.787234 (-1800 2700);
PAINT MONO (-1800 2700);
DISPLAY INVISIBLE (-1800 2700);
FORCEPROP 1 LAST BODY_TYPE PLUMBING
J 2
(-1800 2650);
DISPLAY 1.234043 (-1800 2650);
PAINT GREEN (-1800 2650);
DISPLAY INVISIBLE (-1800 2650);
FORCEPROP 1 LAST HDL_TAP TRUE
J 2
(-2125 2575);
DISPLAY 1.234043 (-2125 2575);
PAINT GREEN (-2125 2575);
DISPLAY INVISIBLE (-2125 2575);
FORCEPROP 1 LAST PATH I93
J 2
(-1800 2700);
DISPLAY 0.936170 (-1800 2700);
PAINT GREEN (-1800 2700);
DISPLAY INVISIBLE (-1800 2700);
FORCEADD TAP..6
R 2
(-1800 2400);
FORCEPROP 3 LASTPIN (-1850 2400) SIG_NAME M_J_DQ<14>
J 0
(-1840 2410);
DISPLAY 0.659574 (-1840 2410);
PAINT MONO (-1840 2410);
DISPLAY INVISIBLE (-1840 2410);
FORCEPROP 1 LASTPIN (-1850 2400) BN 14
J 2
(-1800 2410);
DISPLAY 0.617021 (-1800 2410);
PAINT PINK (-1800 2410);
FORCEPROP 2 LAST CDS_LIB mstr_standard
J 2
(-1800 2400);
DISPLAY 0.787234 (-1800 2400);
PAINT MONO (-1800 2400);
DISPLAY INVISIBLE (-1800 2400);
FORCEPROP 1 LAST BODY_TYPE PLUMBING
J 2
(-1800 2350);
DISPLAY 1.234043 (-1800 2350);
PAINT GREEN (-1800 2350);
DISPLAY INVISIBLE (-1800 2350);
FORCEPROP 1 LAST HDL_TAP TRUE
J 2
(-2125 2275);
DISPLAY 1.234043 (-2125 2275);
PAINT GREEN (-2125 2275);
DISPLAY INVISIBLE (-2125 2275);
FORCEPROP 1 LAST PATH I94
J 2
(-1800 2400);
DISPLAY 0.936170 (-1800 2400);
PAINT GREEN (-1800 2400);
DISPLAY INVISIBLE (-1800 2400);
FORCEADD TAP..6
R 2
(-1800 2350);
FORCEPROP 3 LASTPIN (-1850 2350) SIG_NAME M_J_DQ<15>
J 0
(-1840 2360);
DISPLAY 0.659574 (-1840 2360);
PAINT MONO (-1840 2360);
DISPLAY INVISIBLE (-1840 2360);
FORCEPROP 1 LASTPIN (-1850 2350) BN 15
J 2
(-1800 2360);
DISPLAY 0.617021 (-1800 2360);
PAINT PINK (-1800 2360);
FORCEPROP 2 LAST CDS_LIB mstr_standard
J 2
(-1800 2350);
DISPLAY 0.787234 (-1800 2350);
PAINT MONO (-1800 2350);
DISPLAY INVISIBLE (-1800 2350);
FORCEPROP 1 LAST BODY_TYPE PLUMBING
J 2
(-1800 2300);
DISPLAY 1.234043 (-1800 2300);
PAINT GREEN (-1800 2300);
DISPLAY INVISIBLE (-1800 2300);
FORCEPROP 1 LAST HDL_TAP TRUE
J 2
(-2125 2225);
DISPLAY 1.234043 (-2125 2225);
PAINT GREEN (-2125 2225);
DISPLAY INVISIBLE (-2125 2225);
FORCEPROP 1 LAST PATH I95
J 2
(-1800 2350);
DISPLAY 0.936170 (-1800 2350);
PAINT GREEN (-1800 2350);
DISPLAY INVISIBLE (-1800 2350);
FORCEADD TAP..6
R 2
(-1800 2250);
FORCEPROP 3 LASTPIN (-1850 2250) SIG_NAME M_J_DQ<13>
J 0
(-1840 2260);
DISPLAY 0.659574 (-1840 2260);
PAINT MONO (-1840 2260);
DISPLAY INVISIBLE (-1840 2260);
FORCEPROP 1 LASTPIN (-1850 2250) BN 13
J 2
(-1800 2260);
DISPLAY 0.617021 (-1800 2260);
PAINT PINK (-1800 2260);
FORCEPROP 2 LAST CDS_LIB mstr_standard
J 2
(-1800 2250);
DISPLAY 0.787234 (-1800 2250);
PAINT MONO (-1800 2250);
DISPLAY INVISIBLE (-1800 2250);
FORCEPROP 1 LAST BODY_TYPE PLUMBING
J 2
(-1800 2200);
DISPLAY 1.234043 (-1800 2200);
PAINT GREEN (-1800 2200);
DISPLAY INVISIBLE (-1800 2200);
FORCEPROP 1 LAST HDL_TAP TRUE
J 2
(-2125 2125);
DISPLAY 1.234043 (-2125 2125);
PAINT GREEN (-2125 2125);
DISPLAY INVISIBLE (-2125 2125);
FORCEPROP 1 LAST PATH I96
J 2
(-1800 2250);
DISPLAY 0.936170 (-1800 2250);
PAINT GREEN (-1800 2250);
DISPLAY INVISIBLE (-1800 2250);
FORCEADD TAP..6
R 2
(-1800 2300);
FORCEPROP 3 LASTPIN (-1850 2300) SIG_NAME M_J_DQ<12>
J 0
(-1840 2310);
DISPLAY 0.659574 (-1840 2310);
PAINT MONO (-1840 2310);
DISPLAY INVISIBLE (-1840 2310);
FORCEPROP 1 LASTPIN (-1850 2300) BN 12
J 2
(-1800 2310);
DISPLAY 0.617021 (-1800 2310);
PAINT PINK (-1800 2310);
FORCEPROP 2 LAST CDS_LIB mstr_standard
J 2
(-1800 2300);
DISPLAY 0.787234 (-1800 2300);
PAINT MONO (-1800 2300);
DISPLAY INVISIBLE (-1800 2300);
FORCEPROP 1 LAST BODY_TYPE PLUMBING
J 2
(-1800 2250);
DISPLAY 1.234043 (-1800 2250);
PAINT GREEN (-1800 2250);
DISPLAY INVISIBLE (-1800 2250);
FORCEPROP 1 LAST HDL_TAP TRUE
J 2
(-2125 2175);
DISPLAY 1.234043 (-2125 2175);
PAINT GREEN (-2125 2175);
DISPLAY INVISIBLE (-2125 2175);
FORCEPROP 1 LAST PATH I97
J 2
(-1800 2300);
DISPLAY 0.936170 (-1800 2300);
PAINT GREEN (-1800 2300);
DISPLAY INVISIBLE (-1800 2300);
FORCEADD TAP..6
R 2
(-1800 2450);
FORCEPROP 3 LASTPIN (-1850 2450) SIG_NAME M_J_DQ<17>
J 0
(-1840 2460);
DISPLAY 0.659574 (-1840 2460);
PAINT MONO (-1840 2460);
DISPLAY INVISIBLE (-1840 2460);
FORCEPROP 1 LASTPIN (-1850 2450) BN 17
J 2
(-1800 2460);
DISPLAY 0.617021 (-1800 2460);
PAINT PINK (-1800 2460);
FORCEPROP 2 LAST CDS_LIB mstr_standard
J 2
(-1800 2450);
DISPLAY 0.787234 (-1800 2450);
PAINT MONO (-1800 2450);
DISPLAY INVISIBLE (-1800 2450);
FORCEPROP 1 LAST BODY_TYPE PLUMBING
J 2
(-1800 2400);
DISPLAY 1.234043 (-1800 2400);
PAINT GREEN (-1800 2400);
DISPLAY INVISIBLE (-1800 2400);
FORCEPROP 1 LAST HDL_TAP TRUE
J 2
(-2125 2325);
DISPLAY 1.234043 (-2125 2325);
PAINT GREEN (-2125 2325);
DISPLAY INVISIBLE (-2125 2325);
FORCEPROP 1 LAST PATH I98
J 2
(-1800 2450);
DISPLAY 0.936170 (-1800 2450);
PAINT GREEN (-1800 2450);
DISPLAY INVISIBLE (-1800 2450);
FORCEADD TAP..6
R 2
(-1800 2200);
FORCEPROP 3 LASTPIN (-1850 2200) SIG_NAME M_J_DQ<10>
J 0
(-1840 2210);
DISPLAY 0.659574 (-1840 2210);
PAINT MONO (-1840 2210);
DISPLAY INVISIBLE (-1840 2210);
FORCEPROP 1 LASTPIN (-1850 2200) BN 10
J 2
(-1800 2210);
DISPLAY 0.617021 (-1800 2210);
PAINT PINK (-1800 2210);
FORCEPROP 2 LAST CDS_LIB mstr_standard
J 2
(-1800 2200);
DISPLAY 0.787234 (-1800 2200);
PAINT MONO (-1800 2200);
DISPLAY INVISIBLE (-1800 2200);
FORCEPROP 1 LAST BODY_TYPE PLUMBING
J 2
(-1800 2150);
DISPLAY 1.234043 (-1800 2150);
PAINT GREEN (-1800 2150);
DISPLAY INVISIBLE (-1800 2150);
FORCEPROP 1 LAST HDL_TAP TRUE
J 2
(-2125 2075);
DISPLAY 1.234043 (-2125 2075);
PAINT GREEN (-2125 2075);
DISPLAY INVISIBLE (-2125 2075);
FORCEPROP 1 LAST PATH I99
J 2
(-1800 2200);
DISPLAY 0.936170 (-1800 2200);
PAINT GREEN (-1800 2200);
DISPLAY INVISIBLE (-1800 2200);
FORCEADD BOM_NOTE..1
(-5050 5275);
FORCEPROP 0 LAST L1 STUFF FOR SKU A & B
J 0
(-5200 5175);
DISPLAY 1.063830 (-5200 5175);
PAINT WHITE (-5200 5175);
FORCEPROP 2 LAST CDS_LIB mstr_symbols
J 0
(-5050 5275);
PAINT ORANGE (-5050 5275);
DISPLAY INVISIBLE (-5050 5275);
FORCEPROP 2 LAST BOM_COST SB
J 0
(-5200 5250);
DISPLAY 1.361702 (-5200 5250);
PAINT ORANGE (-5200 5250);
DISPLAY INVISIBLE (-5200 5250);
FORCEPROP 1 LAST COMMENT_BODY TRUE
J 0
(-5025 5375);
DISPLAY 1.319149 (-5025 5375);
PAINT ORANGE (-5025 5375);
DISPLAY INVISIBLE (-5025 5375);
FORCEPROP 2 LAST ROOM SB_HEADERS
J 0
(-5200 5250);
DISPLAY 1.361702 (-5200 5250);
PAINT ORANGE (-5200 5250);
DISPLAY INVISIBLE (-5200 5250);
FORCEADD INTEL_CORP_BPAGE..1
(2650 500);
FORCEPROP 1 LAST CDS_CON_LAST_MODIFIED Tue Dec 01 11:51:43 2015
J 0
(1225 825);
DISPLAY 0.787234 (1225 825);
PAINT ORANGE (1225 825);
DISPLAY INVISIBLE (1225 825);
FORCEPROP 1 LAST CUSTOM_TXT_CDS <CURRENT_DESIGN_SHEET> OF <TOTAL_DESIGN_SHEETS>
J 0
(2150 525);
PAINT GREEN (2150 525);
FORCEPROP 1 LAST CUSTOM_TXT_CDS <CON_LAST_MODIFIED>
J 0
(725 850);
PAINT GREEN (725 850);
FORCEPROP 2 LAST CUSTOM_TXT_CDS <XR_PAGE_TITLE>
J 0
(-5240 5750);
DISPLAY 0.638298 (-5240 5750);
PAINT PINK (-5240 5750);
DISPLAY INVISIBLE (-5240 5750);
FORCEPROP 1 LAST SCH_ADDRESS3 Santa Clara, CA 95052-8119
J 0
(-1325 525);
DISPLAY 0.617021 (-1325 525);
PAINT GREEN (-1325 525);
FORCEPROP 1 LAST SCH_ADDRESS2 P.O. BOX 58119
J 0
(-1325 575);
DISPLAY 0.617021 (-1325 575);
PAINT GREEN (-1325 575);
FORCEPROP 1 LAST SCH_ADDRESS1 2200 Mission College Blvd.
J 0
(-1325 625);
DISPLAY 0.617021 (-1325 625);
PAINT GREEN (-1325 625);
FORCEPROP 1 LAST SCH_TITLE CPU1 DDR4 CH J DIMM0
J 0
(-5275 550);
DISPLAY 1.212766 (-5275 550);
PAINT WHITE (-5275 550);
FORCEPROP 1 LAST SCH_NUMBER H4694802
J 0
(1350 650);
DISPLAY 1.212766 (1350 650);
PAINT YELLOW (1350 650);
FORCEPROP 1 LAST SCH_DEPT BESD
J 1
(-1800 600);
DISPLAY 1.212766 (-1800 600);
PAINT YELLOW (-1800 600);
FORCEPROP 1 LAST SCH_REV 2.420
J 0
(2400 650);
DISPLAY 0.978723 (2400 650);
PAINT YELLOW (2400 650);
FORCEPROP 2 LAST CDS_LIB mstr_symbols
J 0
(2650 500);
DISPLAY 0.787234 (2650 500);
PAINT MONO (2650 500);
DISPLAY INVISIBLE (2650 500);
FORCEPROP 2 LAST PAGE_BORDER TRUE
J 0
(-5240 5750);
DISPLAY 0.680851 (-5240 5750);
PAINT PINK (-5240 5750);
DISPLAY INVISIBLE (-5240 5750);
FORCEPROP 1 LAST COMMENT_BODY TRUE
J 0
(2660 510);
DISPLAY 0.382979 (2660 510);
PAINT GREEN (2660 510);
DISPLAY INVISIBLE (2660 510);
FORCEPROP 2 LAST CDS_XR_PAGE_TITLE CR-81 : @BASEBOARD_FAB2_LIB.BASEBOARD_FAB2(SCH_1):PAGE81
J 0
(-5240 5750);
DISPLAY 0.638298 (-5240 5750);
PAINT PINK (-5240 5750);
DISPLAY INVISIBLE (-5240 5750);
WIRE 17 -1 (700 5175)(700 5200);
WIRE 17 -1 (700 5075)(700 5175);
WIRE 17 -1 (1500 5200)(700 5200);
FORCEPROP 2 LAST SIG_NAME M_J_DQS_DP<17:0>
J 0
(950 5210);
DISPLAY 0.617021 (950 5210);
PAINT ORANGE (950 5210);
WIRE 17 -1 (900 4425)(900 4525);
WIRE 17 -1 (900 4325)(900 4425);
WIRE 17 -1 (900 4525)(900 4625);
WIRE 17 -1 (900 4625)(900 4725);
WIRE 17 -1 (900 4225)(900 4325);
WIRE 17 -1 (900 4125)(900 4225);
WIRE 17 -1 (900 4725)(900 4825);
WIRE 17 -1 (900 4825)(900 4925);
WIRE 17 -1 (900 4025)(900 4125);
WIRE 17 -1 (900 3925)(900 4025);
WIRE 17 -1 (900 4925)(900 5025);
WIRE 17 -1 (900 5025)(900 5125);
WIRE 17 -1 (900 3825)(900 3925);
WIRE 17 -1 (900 3725)(900 3825);
WIRE 17 -1 (900 5125)(900 5150);
WIRE 17 -1 (1500 5150)(900 5150);
FORCEPROP 2 LAST SIG_NAME M_J_DQS_DN<17:0>
J 0
(950 5160);
DISPLAY 0.617021 (950 5160);
PAINT ORANGE (950 5160);
WIRE 17 -1 (700 4475)(700 4575);
WIRE 17 -1 (700 4375)(700 4475);
WIRE 17 -1 (700 4575)(700 4675);
WIRE 17 -1 (700 4675)(700 4775);
WIRE 17 -1 (700 4275)(700 4375);
WIRE 17 -1 (700 4175)(700 4275);
WIRE 17 -1 (700 4775)(700 4875);
WIRE 17 -1 (700 4875)(700 4975);
WIRE 17 -1 (700 4075)(700 4175);
WIRE 17 -1 (700 3975)(700 4075);
WIRE 17 -1 (700 4975)(700 5075);
WIRE 17 -1 (700 3875)(700 3975);
WIRE 17 -1 (700 3775)(700 3875);
WIRE 17 -1 (900 3625)(900 3725);
WIRE 17 -1 (900 3525)(900 3625);
WIRE 17 -1 (900 3425)(900 3525);
WIRE 17 -1 (700 3675)(700 3775);
WIRE 17 -1 (700 3575)(700 3675);
WIRE 17 -1 (700 3475)(700 3575);
WIRE 17 -1 (-1750 4675)(-1750 4725);
WIRE 17 -1 (-1750 4625)(-1750 4675);
WIRE 17 -1 (-1750 4725)(-1750 4775);
WIRE 17 -1 (-1750 4775)(-1750 4825);
WIRE 17 -1 (-1750 4575)(-1750 4625);
WIRE 17 -1 (-1750 4525)(-1750 4575);
WIRE 17 -1 (-1750 4825)(-1750 4850);
WIRE 17 -1 (-1350 4850)(-1750 4850);
FORCEPROP 2 LAST SIG_NAME M_J_DQ<63:0>
J 0
(-1710 4860);
DISPLAY 0.617021 (-1710 4860);
PAINT ORANGE (-1710 4860);
WIRE 17 -1 (-1750 4475)(-1750 4525);
WIRE 17 -1 (-1750 4425)(-1750 4475);
WIRE 17 -1 (-1750 4375)(-1750 4425);
WIRE 17 -1 (-1750 4325)(-1750 4375);
WIRE 17 -1 (-1750 4275)(-1750 4325);
WIRE 17 -1 (-1750 4225)(-1750 4275);
WIRE 17 -1 (-1750 4175)(-1750 4225);
WIRE 17 -1 (-1750 4125)(-1750 4175);
WIRE 17 -1 (-1750 4075)(-1750 4125);
WIRE 17 -1 (-1750 4025)(-1750 4075);
WIRE 17 -1 (-1750 3975)(-1750 4025);
WIRE 17 -1 (-1750 3925)(-1750 3975);
WIRE 17 -1 (-1750 3875)(-1750 3925);
WIRE 17 -1 (-1750 3825)(-1750 3875);
WIRE 17 -1 (-1750 3775)(-1750 3825);
WIRE 17 -1 (-1750 3725)(-1750 3775);
WIRE 17 -1 (-1750 3675)(-1750 3725);
WIRE 17 -1 (-1750 3625)(-1750 3675);
WIRE 17 -1 (-1750 3575)(-1750 3625);
WIRE 17 -1 (-1750 3525)(-1750 3575);
WIRE 17 -1 (-1750 3475)(-1750 3525);
WIRE 17 -1 (-1750 3425)(-1750 3475);
WIRE 17 -1 (-1750 3375)(-1750 3425);
WIRE 17 -1 (-3350 4575)(-3350 4625);
WIRE 17 -1 (-3350 4525)(-3350 4575);
WIRE 17 -1 (-3350 4625)(-3350 4675);
WIRE 17 -1 (-3350 4675)(-3350 4725);
WIRE 17 -1 (-3350 4475)(-3350 4525);
WIRE 17 -1 (-3350 4425)(-3350 4475);
WIRE 17 -1 (-3350 4725)(-3350 4775);
WIRE 17 -1 (-3350 4775)(-3350 4825);
WIRE 17 -1 (-3350 4375)(-3350 4425);
WIRE 17 -1 (-3350 4325)(-3350 4375);
WIRE 17 -1 (-3350 4825)(-3350 4850);
WIRE 17 -1 (-3900 4850)(-3350 4850);
FORCEPROP 2 LAST SIG_NAME M_J_MA<17:0>
J 0
(-3875 4860);
DISPLAY 0.617021 (-3875 4860);
PAINT ORANGE (-3875 4860);
WIRE 17 -1 (-3350 4125)(-3350 4175);
WIRE 17 -1 (-3350 4075)(-3350 4125);
WIRE 17 -1 (-3350 4175)(-3350 4225);
WIRE 17 -1 (-3350 4225)(-3350 4275);
WIRE 17 -1 (-3350 4025)(-3350 4075);
WIRE 17 -1 (-3350 3975)(-3350 4025);
WIRE 17 -1 (-3350 4275)(-3350 4325);
WIRE 17 -1 (-1750 2525)(-1750 2575);
WIRE 17 -1 (-1750 2475)(-1750 2525);
WIRE 17 -1 (-1750 2575)(-1750 2625);
WIRE 17 -1 (-1750 2625)(-1750 2675);
WIRE 17 -1 (-1750 2425)(-1750 2475);
WIRE 17 -1 (-1750 2375)(-1750 2425);
WIRE 17 -1 (-1750 2675)(-1750 2725);
WIRE 17 -1 (-1750 2725)(-1750 2775);
WIRE 17 -1 (-1750 2325)(-1750 2375);
WIRE 17 -1 (-1750 2275)(-1750 2325);
WIRE 17 -1 (-1750 2775)(-1750 2825);
WIRE 17 -1 (-1750 2825)(-1750 2875);
WIRE 17 -1 (-1750 2225)(-1750 2275);
WIRE 17 -1 (-1750 2175)(-1750 2225);
WIRE 17 -1 (-1750 2875)(-1750 2925);
WIRE 17 -1 (-1750 2925)(-1750 2975);
WIRE 17 -1 (-1750 2125)(-1750 2175);
WIRE 17 -1 (-1750 2075)(-1750 2125);
WIRE 17 -1 (-1750 2975)(-1750 3025);
WIRE 17 -1 (-1750 3025)(-1750 3075);
WIRE 17 -1 (-1750 2025)(-1750 2075);
WIRE 17 -1 (-1750 1975)(-1750 2025);
WIRE 17 -1 (-1750 3075)(-1750 3125);
WIRE 17 -1 (-1750 3125)(-1750 3175);
WIRE 17 -1 (-1750 1925)(-1750 1975);
WIRE 17 -1 (-1750 1875)(-1750 1925);
WIRE 17 -1 (-1750 3175)(-1750 3225);
WIRE 17 -1 (-1750 3225)(-1750 3275);
WIRE 17 -1 (-1750 1825)(-1750 1875);
WIRE 17 -1 (-1750 1775)(-1750 1825);
WIRE 17 -1 (-1750 3275)(-1750 3325);
WIRE 17 -1 (-1750 3325)(-1750 3375);
WIRE 17 -1 (-1750 1725)(-1750 1775);
WIRE 17 -1 (-1750 1675)(-1750 1725);
WIRE 17 -1 (-3650 3625)(-3650 3650);
WIRE 17 -1 (-3650 3525)(-3650 3625);
WIRE 17 -1 (-3650 3650)(-4250 3650);
FORCEPROP 2 LAST SIG_NAME M_J_CLK_DP<3:0>
J 0
(-4225 3660);
DISPLAY 0.617021 (-4225 3660);
PAINT ORANGE (-4225 3660);
WIRE 17 -1 (-3800 3575)(-3800 3600);
WIRE 17 -1 (-3800 3575)(-3800 3475);
WIRE 17 -1 (-3800 3600)(-4250 3600);
FORCEPROP 2 LAST SIG_NAME M_J_CLK_DN<3:0>
J 0
(-4225 3610);
DISPLAY 0.617021 (-4225 3610);
PAINT ORANGE (-4225 3610);
WIRE 17 -1 (-3350 3325)(-3350 3350);
FORCEPROP 2 LAST SIG_NAME M_J_CS_N<7:0>
J 0
(-3875 3360);
DISPLAY 0.617021 (-3875 3360);
PAINT ORANGE (-3875 3360);
WIRE 17 -1 (-3350 3275)(-3350 3325);
WIRE 17 -1 (-3350 3225)(-3350 3275);
WIRE 17 -1 (-3350 3775)(-3350 3800);
WIRE 17 -1 (-3350 3725)(-3350 3775);
WIRE 17 -1 (-3350 3800)(-3900 3800);
FORCEPROP 2 LAST SIG_NAME M_J_BG<1:0>
J 0
(-3875 3810);
DISPLAY 0.617021 (-3875 3810);
PAINT ORANGE (-3875 3810);
WIRE 17 -1 (-3350 3825)(-3350 3875);
WIRE 17 -1 (-3350 3900)(-3350 3875);
WIRE 17 -1 (-3350 3900)(-3900 3900);
FORCEPROP 2 LAST SIG_NAME M_J_BA<1:0>
J 0
(-3875 3910);
DISPLAY 0.617021 (-3875 3910);
PAINT ORANGE (-3875 3910);
WIRE 17 -1 (-3350 3175)(-3350 3225);
WIRE 17 -1 (-3350 2725)(-3350 2775);
WIRE 17 -1 (-3350 2675)(-3350 2725);
WIRE 17 -1 (-3350 2775)(-3350 2800);
WIRE 17 -1 (-3350 2800)(-3900 2800);
FORCEPROP 2 LAST SIG_NAME M_J_ECC<7:0>
J 0
(-3875 2810);
DISPLAY 0.617021 (-3875 2810);
PAINT ORANGE (-3875 2810);
WIRE 17 -1 (-3350 2625)(-3350 2675);
WIRE 17 -1 (-3350 2575)(-3350 2625);
WIRE 17 -1 (-3350 2525)(-3350 2575);
WIRE 17 -1 (-3350 2475)(-3350 2525);
WIRE 17 -1 (-3350 2425)(-3350 2475);
WIRE 17 -1 (-3350 3075)(-3350 3100);
WIRE 17 -1 (-3350 3025)(-3350 3075);
WIRE 17 -1 (-3350 3100)(-3900 3100);
FORCEPROP 2 LAST SIG_NAME M_J_CKE<3:0>
J 0
(-3875 3110);
DISPLAY 0.617021 (-3875 3110);
PAINT ORANGE (-3875 3110);
WIRE 17 -1 (-3350 2875)(-3350 2925);
WIRE 17 -1 (-3350 2925)(-3350 2950);
WIRE 17 -1 (-3350 2950)(-3900 2950);
FORCEPROP 2 LAST SIG_NAME M_J_ODT<3:0>
J 0
(-3875 2960);
DISPLAY 0.617021 (-3875 2960);
PAINT ORANGE (-3875 2960);
WIRE 16 -1 (-1050 1150)(-850 1150);
WIRE 16 -1 (-1050 1150)(-1050 1200);
WIRE 16 -1 (-1050 1200)(-850 1200);
WIRE 16 -1 (-1050 1200)(-1050 1250);
WIRE 16 -1 (-1050 1250)(-850 1250);
WIRE 16 -1 (-1050 1250)(-1050 1300);
WIRE 16 -1 (-1050 1300)(-850 1300);
WIRE 16 -1 (-1050 1300)(-1050 1350);
WIRE 16 -1 (-1050 1350)(-850 1350);
WIRE 16 -1 (-1050 1350)(-1050 1400);
WIRE 16 -1 (-1050 1400)(-850 1400);
WIRE 16 -1 (-1050 1400)(-1050 1450);
WIRE 16 -1 (-1050 1450)(-850 1450);
WIRE 16 -1 (-1050 1450)(-1050 1500);
WIRE 16 -1 (-1050 1500)(-850 1500);
WIRE 16 -1 (-1050 1500)(-1050 1550);
WIRE 16 -1 (-1050 1550)(-850 1550);
WIRE 16 -1 (-1050 1550)(-1050 1600);
WIRE 16 -1 (-1050 1600)(-850 1600);
WIRE 16 -1 (-1050 1600)(-1050 1650);
WIRE 16 -1 (-1050 1650)(-850 1650);
WIRE 16 -1 (-1050 1650)(-1050 1700);
WIRE 16 -1 (-1050 1700)(-850 1700);
WIRE 16 -1 (-1050 1700)(-1050 1750);
WIRE 16 -1 (-1050 1750)(-850 1750);
WIRE 16 -1 (-1050 1750)(-1050 1800);
WIRE 16 -1 (-1050 1800)(-850 1800);
WIRE 16 -1 (-1050 1800)(-1050 1850);
WIRE 16 -1 (-1050 1850)(-850 1850);
WIRE 16 -1 (-1050 1850)(-1050 1900);
WIRE 16 -1 (-1050 1900)(-850 1900);
WIRE 16 -1 (-1050 1900)(-1050 1950);
WIRE 16 -1 (-1050 1950)(-850 1950);
WIRE 16 -1 (-1050 1950)(-1050 2000);
WIRE 16 -1 (-1050 2000)(-1050 2050);
WIRE 16 -1 (-1050 2000)(-850 2000);
WIRE 16 -1 (-1050 2050)(-850 2050);
WIRE 16 -1 (-1050 2050)(-1050 2100);
WIRE 16 -1 (-1050 2100)(-850 2100);
WIRE 16 -1 (-1050 2100)(-1050 2150);
WIRE 16 -1 (-1050 2150)(-850 2150);
WIRE 16 -1 (-1050 2150)(-1050 2200);
WIRE 16 -1 (-1050 2200)(-850 2200);
WIRE 16 -1 (-1050 2200)(-1050 2250);
WIRE 16 -1 (-1050 2250)(-850 2250);
WIRE 16 -1 (-1050 2250)(-1050 2300);
WIRE 16 -1 (-1050 2300)(-850 2300);
WIRE 16 -1 (-1050 2300)(-1050 2350);
WIRE 16 -1 (-1050 2350)(-850 2350);
WIRE 16 -1 (-1050 2350)(-1050 2400);
WIRE 16 -1 (-1050 2400)(-850 2400);
WIRE 16 -1 (-1475 2400)(-1050 2400);
WIRE 16 -1 (-1475 2475)(-1475 2400);
WIRE 16 -1 (2250 3550)(2450 3550);
WIRE 16 -1 (2450 3500)(2450 3550);
WIRE 16 -1 (2250 3500)(2450 3500);
WIRE 16 -1 (2450 3450)(2450 3500);
WIRE 16 -1 (2250 3450)(2450 3450);
WIRE 16 -1 (2450 3400)(2450 3450);
WIRE 16 -1 (2250 3400)(2450 3400);
WIRE 16 -1 (2450 3350)(2450 3400);
WIRE 16 -1 (2250 3350)(2450 3350);
WIRE 16 -1 (2450 3300)(2450 3350);
WIRE 16 -1 (2250 3300)(2450 3300);
WIRE 16 -1 (2450 3250)(2450 3300);
WIRE 16 -1 (2250 3250)(2450 3250);
WIRE 16 -1 (2450 3200)(2450 3250);
WIRE 16 -1 (2250 3200)(2450 3200);
WIRE 16 -1 (2450 3150)(2450 3200);
WIRE 16 -1 (2250 3150)(2450 3150);
WIRE 16 -1 (2450 3100)(2450 3150);
WIRE 16 -1 (2250 3100)(2450 3100);
WIRE 16 -1 (2450 3050)(2450 3100);
WIRE 16 -1 (2250 3050)(2450 3050);
WIRE 16 -1 (2450 3000)(2450 3050);
WIRE 16 -1 (2250 3000)(2450 3000);
WIRE 16 -1 (2450 2950)(2450 3000);
WIRE 16 -1 (2250 2950)(2450 2950);
WIRE 16 -1 (2450 2900)(2450 2950);
WIRE 16 -1 (2250 2900)(2450 2900);
WIRE 16 -1 (2450 2850)(2450 2900);
WIRE 16 -1 (2250 2850)(2450 2850);
WIRE 16 -1 (2450 2800)(2450 2850);
WIRE 16 -1 (2250 2800)(2450 2800);
WIRE 16 -1 (2450 2750)(2450 2800);
WIRE 16 -1 (2250 2750)(2450 2750);
WIRE 16 -1 (2450 2700)(2450 2750);
WIRE 16 -1 (2250 2700)(2450 2700);
WIRE 16 -1 (2450 2650)(2450 2700);
WIRE 16 -1 (2250 2650)(2450 2650);
WIRE 16 -1 (2450 2600)(2450 2650);
WIRE 16 -1 (2250 2600)(2450 2600);
WIRE 16 -1 (2450 2550)(2450 2600);
WIRE 16 -1 (2450 2500)(2450 2550);
WIRE 16 -1 (2450 2550)(2250 2550);
WIRE 16 -1 (2250 2500)(2450 2500);
WIRE 16 -1 (2450 2450)(2450 2500);
WIRE 16 -1 (2450 2400)(2450 2450);
WIRE 16 -1 (2450 2450)(2250 2450);
WIRE 16 -1 (2450 2350)(2450 2400);
WIRE 16 -1 (2450 2400)(2250 2400);
WIRE 16 -1 (2450 2300)(2450 2350);
WIRE 16 -1 (2450 2350)(2250 2350);
WIRE 16 -1 (2450 2250)(2450 2300);
WIRE 16 -1 (2450 2300)(2250 2300);
WIRE 16 -1 (2450 2200)(2450 2250);
WIRE 16 -1 (2450 2250)(2250 2250);
WIRE 16 -1 (2450 2150)(2450 2200);
WIRE 16 -1 (2450 2200)(2250 2200);
WIRE 16 -1 (2450 2100)(2450 2150);
WIRE 16 -1 (2450 2150)(2250 2150);
WIRE 16 -1 (2450 2050)(2450 2100);
WIRE 16 -1 (2450 2100)(2250 2100);
WIRE 16 -1 (2450 2050)(2250 2050);
WIRE 16 -1 (2450 2000)(2450 2050);
WIRE 16 -1 (2450 1950)(2450 2000);
WIRE 16 -1 (2450 2000)(2250 2000);
WIRE 16 -1 (2450 1900)(2450 1950);
WIRE 16 -1 (2450 1950)(2250 1950);
WIRE 16 -1 (2450 1850)(2450 1900);
WIRE 16 -1 (2450 1900)(2250 1900);
WIRE 16 -1 (2450 1800)(2450 1850);
WIRE 16 -1 (2450 1850)(2250 1850);
WIRE 16 -1 (2450 1750)(2450 1800);
WIRE 16 -1 (2450 1800)(2250 1800);
WIRE 16 -1 (2450 1700)(2450 1750);
WIRE 16 -1 (2450 1750)(2250 1750);
WIRE 16 -1 (2450 1650)(2450 1700);
WIRE 16 -1 (2450 1700)(2250 1700);
WIRE 16 -1 (2450 1600)(2450 1650);
WIRE 16 -1 (2450 1650)(2250 1650);
WIRE 16 -1 (2450 1550)(2450 1600);
WIRE 16 -1 (2450 1600)(2250 1600);
WIRE 16 -1 (2450 1550)(2250 1550);
WIRE 16 -1 (2450 1500)(2450 1550);
WIRE 16 -1 (2250 1500)(2450 1500);
WIRE 16 -1 (2450 1450)(2450 1500);
WIRE 16 -1 (2250 1450)(2450 1450);
WIRE 16 -1 (2450 1400)(2450 1450);
WIRE 16 -1 (2450 1350)(2450 1400);
WIRE 16 -1 (2450 1400)(2250 1400);
WIRE 16 -1 (2450 1300)(2450 1350);
WIRE 16 -1 (2450 1350)(2250 1350);
WIRE 16 -1 (2450 1250)(2450 1300);
WIRE 16 -1 (2450 1300)(2250 1300);
WIRE 16 -1 (2450 1150)(2450 1250);
WIRE 16 -1 (2450 1250)(2250 1250);
WIRE 16 -1 (-3300 1850)(-3050 1850);
WIRE 16 -1 (-3300 1900)(-3300 1850);
WIRE 16 -1 (-3050 1900)(-3300 1900);
WIRE 16 -1 (-3300 1900)(-5200 1900);
WIRE 16 -1 (-5200 1900)(-5200 1800);
WIRE 16 -1 (-4550 1350)(-4550 1250);
WIRE 16 -1 (-1050 2650)(-850 2650);
WIRE 16 -1 (-1050 2700)(-1050 2650);
WIRE 16 -1 (-1050 2700)(-850 2700);
WIRE 16 -1 (-1050 2750)(-1050 2700);
WIRE 16 -1 (-1050 2750)(-850 2750);
WIRE 16 -1 (-1050 2800)(-1050 2750);
WIRE 16 -1 (-1050 2800)(-850 2800);
WIRE 16 -1 (-1050 2850)(-1050 2800);
WIRE 16 -1 (-1050 2850)(-850 2850);
WIRE 16 -1 (-1050 2950)(-1050 2850);
WIRE 16 -1 (-1050 2500)(-850 2500);
WIRE 16 -1 (-1050 2500)(-1050 2550);
WIRE 16 -1 (-1050 2550)(-850 2550);
WIRE 16 -1 (-1200 2550)(-1050 2550);
WIRE 16 -1 (-1200 2650)(-1200 2550);
WIRE 16 -1 (-3300 1950)(-3050 1950);
WIRE 16 -1 (-3300 1950)(-3300 2000);
WIRE 16 -1 (-3050 2000)(-3300 2000);
WIRE 16 -1 (-3300 2000)(-5200 2000);
WIRE 16 -1 (-5200 2100)(-5200 2000);
WIRE 16 -1 (150 2800)(350 2800);
WIRE 16 -1 (350 2800)(350 2850);
WIRE 16 -1 (150 2850)(350 2850);
WIRE 16 -1 (350 2850)(350 2925);
WIRE 16 -1 (1250 3550)(1050 3550);
WIRE 16 -1 (1050 3500)(1050 3550);
WIRE 16 -1 (1250 3500)(1050 3500);
WIRE 16 -1 (1050 3450)(1050 3500);
WIRE 16 -1 (1250 3450)(1050 3450);
WIRE 16 -1 (1050 3400)(1050 3450);
WIRE 16 -1 (1050 3400)(1250 3400);
WIRE 16 -1 (1050 3350)(1050 3400);
WIRE 16 -1 (1250 3350)(1050 3350);
WIRE 16 -1 (1050 3300)(1050 3350);
WIRE 16 -1 (1250 3300)(1050 3300);
WIRE 16 -1 (1050 3250)(1050 3300);
WIRE 16 -1 (1250 3250)(1050 3250);
WIRE 16 -1 (1050 3200)(1050 3250);
WIRE 16 -1 (1250 3200)(1050 3200);
WIRE 16 -1 (1050 3150)(1050 3200);
WIRE 16 -1 (1250 3150)(1050 3150);
WIRE 16 -1 (1050 3100)(1050 3150);
WIRE 16 -1 (1050 3100)(1250 3100);
WIRE 16 -1 (1050 3050)(1050 3100);
WIRE 16 -1 (1250 3050)(1050 3050);
WIRE 16 -1 (1050 3000)(1050 3050);
WIRE 16 -1 (1250 3000)(1050 3000);
WIRE 16 -1 (1050 2950)(1050 3000);
WIRE 16 -1 (1250 2950)(1050 2950);
WIRE 16 -1 (1050 2900)(1050 2950);
WIRE 16 -1 (1250 2900)(1050 2900);
WIRE 16 -1 (1050 2850)(1050 2900);
WIRE 16 -1 (1250 2850)(1050 2850);
WIRE 16 -1 (1050 2800)(1050 2850);
WIRE 16 -1 (1050 2800)(1250 2800);
WIRE 16 -1 (1050 2750)(1050 2800);
WIRE 16 -1 (1250 2750)(1050 2750);
WIRE 16 -1 (1050 2700)(1050 2750);
WIRE 16 -1 (1250 2700)(1050 2700);
WIRE 16 -1 (1050 2650)(1050 2700);
WIRE 16 -1 (1250 2650)(1050 2650);
WIRE 16 -1 (1050 2600)(1050 2650);
WIRE 16 -1 (1250 2600)(1050 2600);
WIRE 16 -1 (1050 2550)(1050 2600);
WIRE 16 -1 (1250 2550)(1050 2550);
WIRE 16 -1 (1050 2500)(1050 2550);
WIRE 16 -1 (1050 2500)(1250 2500);
WIRE 16 -1 (1050 2450)(1050 2500);
WIRE 16 -1 (1250 2450)(1050 2450);
WIRE 16 -1 (1050 2400)(1050 2450);
WIRE 16 -1 (1250 2400)(1050 2400);
WIRE 16 -1 (1050 2350)(1050 2400);
WIRE 16 -1 (1250 2350)(1050 2350);
WIRE 16 -1 (1050 2300)(1050 2350);
WIRE 16 -1 (1250 2300)(1050 2300);
WIRE 16 -1 (1050 2250)(1050 2300);
WIRE 16 -1 (1050 2250)(1250 2250);
WIRE 16 -1 (1050 2200)(1050 2250);
WIRE 16 -1 (1250 2200)(1050 2200);
WIRE 16 -1 (1050 2150)(1050 2200);
WIRE 16 -1 (1250 2150)(1050 2150);
WIRE 16 -1 (1050 2100)(1050 2150);
WIRE 16 -1 (1250 2100)(1050 2100);
WIRE 16 -1 (1050 2050)(1050 2100);
WIRE 16 -1 (1250 2050)(1050 2050);
WIRE 16 -1 (1050 2000)(1050 2050);
WIRE 16 -1 (1050 2000)(1250 2000);
WIRE 16 -1 (1050 1950)(1050 2000);
WIRE 16 -1 (1250 1950)(1050 1950);
WIRE 16 -1 (1050 1900)(1050 1950);
WIRE 16 -1 (1250 1900)(1050 1900);
WIRE 16 -1 (1050 1850)(1050 1900);
WIRE 16 -1 (1250 1850)(1050 1850);
WIRE 16 -1 (1050 1800)(1050 1850);
WIRE 16 -1 (1250 1800)(1050 1800);
WIRE 16 -1 (1050 1750)(1050 1800);
WIRE 16 -1 (1050 1750)(1250 1750);
WIRE 16 -1 (1050 1700)(1050 1750);
WIRE 16 -1 (1250 1700)(1050 1700);
WIRE 16 -1 (1050 1650)(1050 1700);
WIRE 16 -1 (1250 1650)(1050 1650);
WIRE 16 -1 (1050 1600)(1050 1650);
WIRE 16 -1 (1250 1600)(1050 1600);
WIRE 16 -1 (1050 1550)(1050 1600);
WIRE 16 -1 (1250 1550)(1050 1550);
WIRE 16 -1 (1050 1500)(1050 1550);
WIRE 16 -1 (1050 1500)(1250 1500);
WIRE 16 -1 (1050 1450)(1050 1500);
WIRE 16 -1 (1250 1450)(1050 1450);
WIRE 16 -1 (1050 1400)(1050 1450);
WIRE 16 -1 (1250 1400)(1050 1400);
WIRE 16 -1 (1050 1350)(1050 1400);
WIRE 16 -1 (1250 1350)(1050 1350);
WIRE 16 -1 (1050 1300)(1050 1350);
WIRE 16 -1 (1250 1300)(1050 1300);
WIRE 16 -1 (1050 1250)(1050 1300);
WIRE 16 -1 (1250 1250)(1050 1250);
WIRE 16 -1 (1050 1150)(1050 1250);
WIRE 17 -1 (-3350 3350)(-3900 3350);
WIRE 16 -1 (-3500 2200)(-3050 2200);
WIRE 16 -1 (-3500 2200)(-3500 2450);
WIRE 16 -1 (-3500 2450)(-4275 2450);
FORCEPROP 2 LAST SIG_NAME FM_DIMM_EVENT_COD_N
J 0
(-4231 2467);
DISPLAY 0.617021 (-4231 2467);
PAINT ORANGE (-4231 2467);
WIRE 16 -1 (-3050 1650)(-4550 1650);
FORCEPROP 2 LAST SIG_NAME M_J_VREF
J 0
(-3850 1660);
DISPLAY 0.617021 (-3850 1660);
PAINT ORANGE (-3850 1660);
WIRE 16 -1 (-4550 1650)(-4550 1550);
WIRE 16 -1 (-4650 1650)(-4550 1650);
WIRE 16 -1 (-3900 1500)(-3050 1500);
FORCEPROP 2 LAST SIG_NAME TP_CH_J_DIMM_J0_RFU_1
J 0
(-3850 1510);
DISPLAY 0.617021 (-3850 1510);
PAINT ORANGE (-3850 1510);
FORCEPROP 2 LASTPROP $XRERR UNIQUE?
J 0
(-4140 1500);
DISPLAY 0.638298 (-4140 1500);
PAINT MONO (-4140 1500);
DISPLAY INVISIBLE (-4140 1500);
WIRE 16 -1 (-3900 1450)(-3050 1450);
FORCEPROP 2 LAST SIG_NAME TP_CH_J_DIMM_J0_RFU_0
J 0
(-3850 1460);
DISPLAY 0.617021 (-3850 1460);
PAINT ORANGE (-3850 1460);
FORCEPROP 2 LASTPROP $XRERR UNIQUE?
J 0
(-4140 1450);
DISPLAY 0.638298 (-4140 1450);
PAINT MONO (-4140 1450);
DISPLAY INVISIBLE (-4140 1450);
WIRE 16 -1 (-3900 1550)(-3050 1550);
FORCEPROP 2 LAST SIG_NAME TP_CH_J_DIMM_J0_RFU_2
J 0
(-3850 1560);
DISPLAY 0.617021 (-3850 1560);
PAINT ORANGE (-3850 1560);
FORCEPROP 2 LASTPROP $XRERR UNIQUE?
J 0
(-4140 1550);
DISPLAY 0.638298 (-4140 1550);
PAINT MONO (-4140 1550);
DISPLAY INVISIBLE (-4140 1550);
WIRE 16 -1 (-3900 1750)(-3050 1750);
FORCEPROP 2 LAST SIG_NAME SMB_DDR_GHJ_VPP_SCL
J 0
(-3860 1760);
DISPLAY 0.617021 (-3860 1760);
PAINT ORANGE (-3860 1760);
WIRE 16 -1 (-3900 1800)(-3050 1800);
WIRE 16 -1 (-3900 1350)(-3050 1350);
FORCEPROP 2 LAST SIG_NAME FM_ADR_COMPLETE_GHJ_N
J 0
(-3850 1360);
DISPLAY 0.617021 (-3850 1360);
PAINT ORANGE (-3850 1360);
WIRE 16 -1 (-3050 2250)(-3450 2250);
WIRE 16 -1 (-3450 2250)(-3450 2700);
WIRE 16 -1 (-3450 2700)(-3900 2700);
FORCEPROP 2 LAST SIG_NAME M_GHJ_RST_N
J 0
(-3875 2710);
DISPLAY 0.617021 (-3875 2710);
PAINT ORANGE (-3875 2710);
WIRE 16 -1 (-3050 2300)(-3400 2300);
WIRE 16 -1 (-3400 2300)(-3400 2750);
WIRE 16 -1 (-3400 2750)(-3900 2750);
FORCEPROP 2 LAST SIG_NAME M_J_PAR
J 0
(-3875 2760);
DISPLAY 0.617021 (-3875 2760);
PAINT ORANGE (-3875 2760);
WIRE 16 -1 (-3150 3350)(-3050 3350);
WIRE 16 -1 (-3150 3400)(-3150 3350);
WIRE 16 -1 (-3150 3400)(-3900 3400);
FORCEPROP 2 LAST SIG_NAME M_J_C<2>
J 0
(-3875 3410);
DISPLAY 0.617021 (-3875 3410);
PAINT ORANGE (-3875 3410);
WIRE 16 -1 (-3050 3150)(-3250 3150);
WIRE 16 -1 (-3050 3000)(-3250 3000);
WIRE 16 -1 (-3050 2900)(-3250 2900);
WIRE 16 -1 (-3050 2850)(-3250 2850);
WIRE 16 -1 (-3050 2750)(-3250 2750);
WIRE 16 -1 (-3050 4050)(-3250 4050);
WIRE 16 -1 (-3050 3700)(-3250 3700);
WIRE 16 -1 (-3050 3050)(-3250 3050);
WIRE 16 -1 (-3050 2400)(-3250 2400);
WIRE 16 -1 (-3050 2450)(-3250 2450);
WIRE 16 -1 (-3050 2500)(-3250 2500);
WIRE 16 -1 (-3050 2550)(-3250 2550);
WIRE 16 -1 (-3050 2600)(-3250 2600);
WIRE 16 -1 (-3050 2650)(-3250 2650);
WIRE 16 -1 (-3050 2700)(-3250 2700);
WIRE 16 -1 (-3050 4000)(-3250 4000);
WIRE 16 -1 (-3050 3950)(-3250 3950);
WIRE 16 -1 (-3050 3200)(-3250 3200);
WIRE 16 -1 (-3050 3850)(-3250 3850);
WIRE 16 -1 (-3050 3800)(-3250 3800);
WIRE 16 -1 (-3050 3750)(-3250 3750);
WIRE 16 -1 (-3050 3250)(-3250 3250);
WIRE 16 -1 (-3050 3300)(-3250 3300);
WIRE 16 -1 (-3050 3450)(-3700 3450);
WIRE 16 -1 (-3050 3500)(-3550 3500);
WIRE 16 -1 (-3050 3550)(-3700 3550);
WIRE 16 -1 (-3050 3600)(-3550 3600);
WIRE 16 -1 (-3050 2100)(-4050 2100);
FORCEPROP 2 LAST SIG_NAME M_J_ACT_N
J 0
(-4000 2110);
DISPLAY 0.617021 (-4000 2110);
PAINT ORANGE (-4000 2110);
WIRE 16 -1 (-3050 2150)(-4075 2150);
FORCEPROP 2 LAST SIG_NAME M_J_ALERT_N
J 0
(-4025 2160);
DISPLAY 0.617021 (-4025 2160);
PAINT ORANGE (-4025 2160);
WIRE 16 -1 (-1850 1900)(-2050 1900);
WIRE 16 -1 (-1850 1850)(-2050 1850);
WIRE 16 -1 (-1850 1800)(-2050 1800);
WIRE 16 -1 (-1850 1750)(-2050 1750);
WIRE 16 -1 (-1850 4000)(-2050 4000);
WIRE 16 -1 (-1850 4050)(-2050 4050);
WIRE 16 -1 (-1850 2400)(-2050 2400);
WIRE 16 -1 (-1850 2950)(-2050 2950);
WIRE 16 -1 (-1850 3000)(-2050 3000);
WIRE 16 -1 (-1850 3550)(-2050 3550);
WIRE 16 -1 (-1850 3450)(-2050 3450);
WIRE 16 -1 (-1850 3400)(-2050 3400);
WIRE 16 -1 (-1850 1650)(-2050 1650);
WIRE 16 -1 (-1850 1700)(-2050 1700);
WIRE 16 -1 (-1850 1950)(-2050 1950);
WIRE 16 -1 (-1850 2000)(-2050 2000);
WIRE 16 -1 (-1850 2050)(-2050 2050);
WIRE 16 -1 (-1850 2100)(-2050 2100);
WIRE 16 -1 (-1850 2200)(-2050 2200);
WIRE 16 -1 (-1850 2250)(-2050 2250);
WIRE 16 -1 (-1850 2300)(-2050 2300);
WIRE 16 -1 (-1850 2350)(-2050 2350);
WIRE 16 -1 (-1850 2450)(-2050 2450);
WIRE 16 -1 (-1850 2550)(-2050 2550);
WIRE 16 -1 (-1850 2600)(-2050 2600);
WIRE 16 -1 (-1850 2650)(-2050 2650);
WIRE 16 -1 (-1850 2700)(-2050 2700);
WIRE 16 -1 (-1850 2750)(-2050 2750);
WIRE 16 -1 (-1850 2800)(-2050 2800);
WIRE 16 -1 (-1850 2850)(-2050 2850);
WIRE 16 -1 (-1850 2900)(-2050 2900);
WIRE 16 -1 (-1850 3150)(-2050 3150);
WIRE 16 -1 (-1850 3200)(-2050 3200);
WIRE 16 -1 (-1850 3250)(-2050 3250);
WIRE 16 -1 (-1850 3300)(-2050 3300);
WIRE 16 -1 (-1850 3350)(-2050 3350);
WIRE 16 -1 (-1850 3500)(-2050 3500);
WIRE 16 -1 (-1850 3600)(-2050 3600);
WIRE 16 -1 (-1850 3650)(-2050 3650);
WIRE 16 -1 (-1850 3700)(-2050 3700);
WIRE 16 -1 (-1850 3750)(-2050 3750);
WIRE 16 -1 (-1850 3800)(-2050 3800);
WIRE 16 -1 (-1850 3850)(-2050 3850);
WIRE 16 -1 (-1850 3900)(-2050 3900);
WIRE 16 -1 (-1850 3950)(-2050 3950);
WIRE 16 -1 (-1850 3050)(-2050 3050);
WIRE 16 -1 (-1850 3100)(-2050 3100);
WIRE 16 -1 (-1850 2150)(-2050 2150);
WIRE 16 -1 (-1850 2500)(-2050 2500);
WIRE 16 -1 (-3050 4750)(-3250 4750);
WIRE 16 -1 (-3050 4700)(-3250 4700);
WIRE 16 -1 (-3050 4650)(-3250 4650);
WIRE 16 -1 (-3050 4500)(-3250 4500);
WIRE 16 -1 (-3050 4450)(-3250 4450);
WIRE 16 -1 (-3050 4400)(-3250 4400);
WIRE 16 -1 (-3050 4350)(-3250 4350);
WIRE 16 -1 (-3050 4300)(-3250 4300);
WIRE 16 -1 (-3050 4250)(-3250 4250);
WIRE 16 -1 (-3050 4200)(-3250 4200);
WIRE 16 -1 (-3050 4150)(-3250 4150);
WIRE 16 -1 (-3050 4100)(-3250 4100);
WIRE 16 -1 (-3050 4800)(-3250 4800);
WIRE 16 -1 (-3050 4600)(-3250 4600);
WIRE 16 -1 (-3050 4550)(-3250 4550);
WIRE 16 -1 (-1850 4800)(-2050 4800);
WIRE 16 -1 (-1850 4750)(-2050 4750);
WIRE 16 -1 (-1850 4700)(-2050 4700);
WIRE 16 -1 (-1850 4100)(-2050 4100);
WIRE 16 -1 (-1850 4150)(-2050 4150);
WIRE 16 -1 (-1850 4200)(-2050 4200);
WIRE 16 -1 (-1850 4250)(-2050 4250);
WIRE 16 -1 (-1850 4300)(-2050 4300);
WIRE 16 -1 (-1850 4350)(-2050 4350);
WIRE 16 -1 (-1850 4550)(-2050 4550);
WIRE 16 -1 (-1850 4500)(-2050 4500);
WIRE 16 -1 (-1850 4400)(-2050 4400);
WIRE 16 -1 (-1850 4450)(-2050 4450);
WIRE 16 -1 (-1850 4600)(-2050 4600);
WIRE 16 -1 (-1850 4650)(-2050 4650);
WIRE 16 -1 (600 4050)(400 4050);
WIRE 16 -1 (800 4000)(400 4000);
WIRE 16 -1 (600 3950)(400 3950);
WIRE 16 -1 (800 3900)(400 3900);
WIRE 16 -1 (600 3850)(400 3850);
WIRE 16 -1 (800 3800)(400 3800);
WIRE 16 -1 (600 3750)(400 3750);
WIRE 16 -1 (800 3700)(400 3700);
WIRE 16 -1 (600 3650)(400 3650);
WIRE 16 -1 (800 3600)(400 3600);
WIRE 16 -1 (600 3550)(400 3550);
WIRE 16 -1 (800 3500)(400 3500);
WIRE 16 -1 (600 3450)(400 3450);
WIRE 16 -1 (800 3400)(400 3400);
WIRE 16 -1 (600 4350)(400 4350);
WIRE 16 -1 (800 4300)(400 4300);
WIRE 16 -1 (600 4250)(400 4250);
WIRE 16 -1 (800 4200)(400 4200);
WIRE 16 -1 (600 4150)(400 4150);
WIRE 16 -1 (800 4100)(400 4100);
WIRE 16 -1 (800 5100)(400 5100);
WIRE 16 -1 (600 5050)(400 5050);
WIRE 16 -1 (800 5000)(400 5000);
WIRE 16 -1 (600 4950)(400 4950);
WIRE 16 -1 (800 4900)(400 4900);
WIRE 16 -1 (600 4850)(400 4850);
WIRE 16 -1 (800 4800)(400 4800);
WIRE 16 -1 (600 4750)(400 4750);
WIRE 16 -1 (800 4700)(400 4700);
WIRE 16 -1 (600 4650)(400 4650);
WIRE 16 -1 (800 4600)(400 4600);
WIRE 16 -1 (600 4550)(400 4550);
WIRE 16 -1 (800 4500)(400 4500);
WIRE 16 -1 (600 4450)(400 4450);
WIRE 16 -1 (800 4400)(400 4400);
WIRE 16 -1 (600 5150)(400 5150);
DOT 1 (-1050 1200);
DOT 1 (2450 1950);
DOT 1 (1050 1350);
DOT 1 (1050 1450);
DOT 1 (2450 1450);
DOT 1 (2450 2900);
DOT 1 (2450 1800);
DOT 1 (2450 1850);
DOT 1 (350 2850);
DOT 1 (-3300 2000);
DOT 1 (1050 1250);
DOT 1 (1050 1300);
DOT 1 (1050 1400);
DOT 1 (1050 1550);
DOT 1 (1050 1500);
DOT 1 (1050 1600);
DOT 1 (1050 1700);
DOT 1 (1050 1650);
DOT 1 (1050 1750);
DOT 1 (1050 1800);
DOT 1 (1050 1850);
DOT 1 (1050 1950);
DOT 1 (1050 2000);
DOT 1 (1050 2050);
DOT 1 (1050 2100);
DOT 1 (1050 2150);
DOT 1 (1050 2200);
DOT 1 (1050 2250);
DOT 1 (1050 2350);
DOT 1 (1050 2300);
DOT 1 (1050 2400);
DOT 1 (1050 2450);
DOT 1 (1050 2500);
DOT 1 (1050 2600);
DOT 1 (1050 2550);
DOT 1 (1050 2650);
DOT 1 (1050 2700);
DOT 1 (1050 2750);
DOT 1 (1050 2850);
DOT 1 (1050 2800);
DOT 1 (1050 2900);
DOT 1 (1050 2950);
DOT 1 (1050 3000);
DOT 1 (1050 3150);
DOT 1 (1050 3100);
DOT 1 (1050 3050);
DOT 1 (1050 3250);
DOT 1 (1050 3200);
DOT 1 (1050 3300);
DOT 1 (1050 3350);
DOT 1 (1050 3400);
DOT 1 (1050 3450);
DOT 1 (1050 3500);
DOT 1 (2450 1250);
DOT 1 (2450 1300);
DOT 1 (2450 1350);
DOT 1 (2450 1400);
DOT 1 (2450 1500);
DOT 1 (2450 1550);
DOT 1 (2450 1600);
DOT 1 (2450 1650);
DOT 1 (2450 1700);
DOT 1 (2450 1750);
DOT 1 (2450 1900);
DOT 1 (2450 2000);
DOT 1 (2450 2050);
DOT 1 (2450 2100);
DOT 1 (2450 2150);
DOT 1 (2450 2200);
DOT 1 (2450 2250);
DOT 1 (2450 2300);
DOT 1 (2450 2350);
DOT 1 (2450 2400);
DOT 1 (2450 2450);
DOT 1 (2450 2500);
DOT 1 (2450 2550);
DOT 1 (2450 2600);
DOT 1 (2450 2650);
DOT 1 (2450 2700);
DOT 1 (2450 2750);
DOT 1 (2450 2800);
DOT 1 (2450 2850);
DOT 1 (2450 2950);
DOT 1 (2450 3000);
DOT 1 (2450 3050);
DOT 1 (2450 3100);
DOT 1 (2450 3150);
DOT 1 (2450 3200);
DOT 1 (2450 3250);
DOT 1 (2450 3300);
DOT 1 (2450 3350);
DOT 1 (2450 3400);
DOT 1 (2450 3450);
DOT 1 (2450 3500);
DOT 1 (-4550 1650);
DOT 1 (-1050 2700);
DOT 1 (-1050 2850);
DOT 1 (-1050 2800);
DOT 1 (-1050 2750);
DOT 1 (-1050 2550);
DOT 1 (-1050 2350);
DOT 1 (-1050 2200);
DOT 1 (-1050 2150);
DOT 1 (-1050 2100);
DOT 1 (-1050 2000);
DOT 1 (-1050 2050);
DOT 1 (-1050 1950);
DOT 1 (-1050 1900);
DOT 1 (-1050 1850);
DOT 1 (-1050 1750);
DOT 1 (-1050 1800);
DOT 1 (-1050 1700);
DOT 1 (-1050 1600);
DOT 1 (-1050 1650);
DOT 1 (-1050 1500);
DOT 1 (-1050 1550);
DOT 1 (-1050 1450);
DOT 1 (-1050 1400);
DOT 1 (-1050 1350);
DOT 1 (-1050 1300);
DOT 1 (-1050 1250);
DOT 1 (1050 1900);
DOT 1 (-3300 1900);
DOT 1 (-1050 2300);
DOT 1 (-1050 2400);
DOT 1 (-1050 2250);
FORCENOTE
PLACE CAP NEAR DIMM CONNECTOR
(-5288 1052) 0;
DISPLAY LEFT (-5288 1052);
DISPLAY 1.957447 (-5288 1052);
PAINT PURPLE (-5288 1052);
FORCENOTE
SMBUS ADDR: 0XA8
(-5250 900) 0;
DISPLAY LEFT (-5250 900);
DISPLAY 1.957447 (-5250 900);
PAINT PURPLE (-5250 900);
QUIT
